%FSTAX23Y23*%
%MOIN*%
%SFA1B1*%

%IPPOS*%
%AMD38*
4,1,8,-0.010500,0.010000,-0.010500,-0.010000,0.000000,-0.020400,0.000000,-0.020400,0.010500,-0.010000,0.010500,0.010000,0.000000,0.020400,0.000000,0.020400,-0.010500,0.010000,0.0*
1,1,0.020960,0.000000,0.010000*
1,1,0.020960,0.000000,-0.010000*
1,1,0.020960,0.000000,-0.010000*
1,1,0.020960,0.000000,0.010000*
%
%ADD14C,0.010000*%
%ADD17C,0.006000*%
%ADD19C,0.005000*%
%ADD22C,0.008000*%
%ADD24C,0.009000*%
%ADD26R,0.028000X0.165000*%
%ADD27R,0.028000X0.126000*%
%ADD28R,0.028350X0.039370*%
%ADD29R,0.027560X0.035430*%
%ADD30R,0.086610X0.041340*%
%ADD31R,0.041340X0.039370*%
%ADD32R,0.037400X0.031500*%
%ADD33R,0.057090X0.045280*%
%ADD34R,0.212600X0.114170*%
%ADD35R,0.041340X0.043310*%
%ADD36R,0.029530X0.033470*%
%ADD37R,0.043310X0.041340*%
G04~CAMADD=38~8~0.0~0.0~408.8~209.5~104.8~0.0~15~0.0~0.0~0.0~0.0~0~0.0~0.0~0.0~0.0~0~0.0~0.0~0.0~90.0~210.0~409.0*
%ADD38D38*%
%ADD39R,0.020950X0.040880*%
%ADD40R,0.035430X0.039370*%
%ADD41R,0.037400X0.033470*%
%ADD42R,0.009840X0.061020*%
%ADD43R,0.066930X0.053150*%
%ADD44R,0.053150X0.066930*%
%ADD45R,0.061020X0.009840*%
%ADD46O,0.078740X0.023620*%
%ADD47R,0.064960X0.051180*%
%ADD48R,0.017720X0.054330*%
%ADD49R,0.055910X0.061020*%
%ADD50R,0.070870X0.074800*%
%ADD51R,0.039370X0.074800*%
%ADD52R,0.019680X0.090550*%
%ADD53R,0.078740X0.098430*%
%ADD54R,0.019680X0.035430*%
%ADD55O,0.057090X0.017720*%
%ADD56R,0.077560X0.022440*%
%ADD57R,0.025590X0.041340*%
%ADD58R,0.051180X0.074800*%
%ADD59R,0.039370X0.090550*%
%ADD60R,0.039370X0.070870*%
%ADD61R,0.053150X0.027560*%
%ADD62R,0.027560X0.045280*%
%ADD63R,0.041340X0.045280*%
%ADD64R,0.050000X0.200000*%
%ADD65R,0.057090X0.037400*%
%ADD66R,0.031500X0.066930*%
%ADD67R,0.070870X0.009840*%
%ADD68R,0.009840X0.022640*%
%ADD69R,0.026570X0.009840*%
%ADD70R,0.038580X0.034250*%
%ADD71R,0.165350X0.125980*%
%ADD72R,0.096460X0.124020*%
%ADD73R,0.033470X0.039370*%
%ADD74R,0.037400X0.039370*%
%ADD75R,0.009840X0.010830*%
%ADD76R,0.010830X0.009840*%
%ADD77R,0.045280X0.057090*%
%ADD78R,0.039370X0.033470*%
%ADD79R,0.039370X0.028350*%
%ADD80R,0.023620X0.025590*%
%ADD81R,0.082870X0.044090*%
%ADD82R,0.039370X0.037400*%
%ADD83R,0.035430X0.027560*%
%ADD142C,0.120000*%
%ADD162C,0.020000*%
%ADD163C,0.012000*%
%ADD164R,0.110430X0.066930*%
%ADD165R,0.105320X0.067910*%
%ADD166C,0.112000*%
%ADD167C,0.021660*%
%ADD168C,0.031500*%
%ADD169C,0.065980*%
%ADD170C,0.061020*%
%ADD171R,0.061020X0.061020*%
%ADD172C,0.075000*%
%ADD173C,0.098430*%
%ADD174O,0.196850X0.098430*%
%ADD175O,0.177170X0.088580*%
%ADD176O,0.088580X0.177170*%
%ADD177C,0.055000*%
%ADD178R,0.055000X0.055000*%
%ADD179C,0.050000*%
%ADD180C,0.250000*%
%ADD181C,0.016000*%
%ADD182C,0.032000*%
%ADD183C,0.200000*%
%LNtimingcard_pcb-1*%
%LPD*%
G36*
X07001Y035D02*
X0647D01*
Y03893*
X07001*
Y035*
G37*
G36*
X0462Y03246D02*
Y02826D01*
X04502Y02708*
X04355*
X04354Y02709*
X04353Y02713*
X04356Y02718*
X04358Y02725*
Y02749*
X04376*
Y02811*
X04303*
Y02749*
X04321*
Y02725*
X04322Y02718*
X04326Y02713*
X04325Y02709*
X04324Y02708*
X0425*
X04249Y02709*
X04248Y02713*
X04251Y02718*
X04253Y02725*
Y02749*
X04271*
Y02811*
X04212*
X0421Y02816*
X04214Y0282*
X04222*
X04223Y0282*
X04271*
Y02833*
X04303*
Y0282*
X04376*
Y02833*
X04384*
X04388Y02829*
X04394Y02825*
X04401Y02823*
X04404*
X04407Y0282*
Y02817*
Y02812*
Y02764*
X04462*
Y02771*
X04503*
X0451Y02772*
X04516Y02776*
X0452Y02782*
X04522Y02789*
X0452Y02796*
X04516Y02802*
X0451Y02806*
X04503Y02808*
X04465*
X04462Y02811*
Y02815*
Y0282*
Y02867*
X04407*
X04402Y02865*
X04398Y02868*
X04391Y02869*
X04376*
Y02882*
X04303*
Y02869*
X04271*
Y02882*
X04198*
Y02854*
X04193Y02851*
X04174Y02833*
X0417Y02827*
X04169Y0282*
Y02815*
X04122*
Y02764*
X04177*
Y02771*
X04183Y02773*
X04189Y02777*
X04193Y02781*
X04198Y02779*
Y02749*
X04216*
Y02725*
X04217Y02718*
X04221Y02713*
X0422Y02709*
X04219Y02708*
X0408*
X04078Y02713*
X04079Y02715*
X04081Y02722*
X04079Y02728*
X04078Y02731*
Y02749*
X04101*
Y02811*
X04028*
Y02749*
X04051*
Y02731*
X04049Y02728*
X04048Y02722*
X04049Y02715*
X04051Y02713*
X04048Y02708*
X03974*
X03973Y0271*
X03972Y02713*
X03975Y02717*
X03977Y02724*
X03975Y0273*
X03973Y02734*
Y02749*
X03996*
Y02811*
X03923*
Y02749*
X03946*
Y02731*
X03945Y0273*
X03944Y02724*
X03945Y02717*
X03948Y02713*
X03948Y0271*
X03946Y02708*
X03846*
Y02811*
X03845Y02815*
X03843Y02819*
X0365Y03012*
Y03276*
X03655Y0328*
X03657Y0328*
X03664Y03281*
X03669Y03284*
X03672Y0329*
X03674Y03296*
X03673Y03298*
X03676Y03301*
X03715*
Y03328*
X03735*
X03738Y03326*
X03744Y03325*
X03751Y03326*
X03756Y0333*
X03759Y03335*
X03761Y03342*
X03759Y03348*
X03756Y03353*
X03751Y03357*
X03744Y03358*
X03738Y03357*
X03735Y03355*
X03715*
Y03357*
X03662*
Y03315*
X03658Y03312*
X03657Y03312*
X03655Y03312*
X0365Y03316*
Y03397*
X03649Y03402*
X03646Y03406*
X03648Y0341*
X03733Y03495*
X04308*
X04312Y03492*
X04318Y03491*
X04325Y03492*
X0433Y03496*
X04333Y03501*
X04335Y03507*
X04333Y03514*
X0433Y03519*
X04325Y03522*
X04318Y03524*
X04312Y03522*
X04308Y0352*
X03728*
X03723Y03519*
X03719Y03516*
X03625Y03422*
X03622Y03418*
X03621Y03413*
Y03401*
X03622Y03396*
X03625Y03392*
X03625Y03392*
Y03007*
X03626Y03003*
X03629Y02999*
X03822Y02805*
Y02708*
X036*
Y0287*
X03599Y02874*
X03597Y02878*
X03578Y02897*
X03574Y029*
X03569Y02901*
X03559*
Y02921*
Y02922*
Y02926*
Y02927*
Y02968*
Y0297*
Y02973*
Y02975*
Y03017*
X03509*
X03506Y03021*
Y03022*
Y03082*
X03497*
Y03087*
X03498Y03087*
X03503Y03091*
X03506Y03096*
X03508Y03103*
X03506Y03109*
X03503Y03114*
X03498Y03118*
X03491Y03119*
X03485Y03118*
X0348Y03114*
X03479Y03113*
X0331*
X03305Y03112*
X03301Y0311*
X03242Y0305*
X03239Y03047*
X03238Y03042*
Y02988*
X03218Y02968*
X03216Y02969*
X03214Y0297*
X03212Y02976*
X03209Y02981*
X03204Y02985*
X03197Y02986*
X03191Y02985*
X03186Y02981*
X03182Y02976*
X03181Y0297*
X03182Y02963*
X03186Y02958*
X03191Y02954*
X03197Y02953*
X03198Y02951*
X03199Y02948*
X03183Y02932*
X0318Y02928*
X03179Y02924*
Y02824*
X0318Y0282*
X03183Y02816*
X03191Y02807*
X03195Y02804*
Y02782*
X03222*
Y02831*
X03242*
Y02858*
X03241*
Y02875*
X03346Y0298*
X03351Y0298*
X03354Y02983*
X03409*
Y02975*
Y02973*
Y0297*
Y02968*
Y02927*
Y02926*
Y02922*
Y02921*
Y02907*
X03408Y02907*
X03403Y02903*
X03399Y02898*
X03398Y02892*
X03399Y02885*
X03403Y0288*
X03408Y02876*
X03409Y02876*
Y02861*
X03471*
Y02824*
X03455*
Y02769*
X03499*
Y02824*
X03498*
Y02861*
X03559*
Y02876*
X03564Y02876*
X03576Y02865*
Y02708*
X03387*
Y02723*
X03404*
X03408Y02721*
X03414Y02719*
X03421Y02721*
X03426Y02724*
X03429Y02729*
X03431Y02736*
X03429Y02742*
X03426Y02747*
X03421Y02751*
X03414Y02752*
X03408Y02751*
X03404Y02748*
X03387*
Y02764*
X03328*
Y02748*
X03304*
X03281Y02771*
Y02782*
X03282*
Y02827*
X03255*
Y02798*
X03236*
Y02771*
X03256*
Y02766*
X03257Y02761*
X0326Y02757*
X0329Y02727*
X03294Y02724*
X03299Y02723*
X03328*
Y02708*
X03155*
Y0276*
X03096*
Y02744*
X03061*
X03057Y02747*
X03051Y02748*
X03044Y02747*
X03039Y02743*
X03036Y02738*
X03034Y02732*
X03036Y02726*
X03039Y0272*
X03044Y02717*
X03051Y02715*
X03057Y02717*
X03061Y0272*
X03096*
Y02708*
X02827*
X02672Y02863*
Y03325*
X02898Y03551*
X04315*
X0462Y03246*
G37*
G36*
X06805Y02702D02*
X06398D01*
Y02702*
X06341*
Y02691*
X06332Y02683*
Y02488*
X06289*
Y02486*
X06116*
X0611Y02481*
X06106Y02482*
Y02771*
X06337*
X06341Y02769*
Y02766*
Y0271*
X06398*
Y02726*
X06441*
X06444Y02725*
X0645Y02723*
X06457Y02725*
X06462Y02728*
X06465Y02733*
X06467Y0274*
X06465Y02746*
X06462Y02751*
X06457Y02755*
X0645Y02756*
X06444Y02755*
X06441Y02753*
X06402*
X06398Y02756*
Y02769*
X06402Y02771*
X0645*
X0646Y02781*
Y02968*
X06805*
Y02702*
G37*
G36*
X06942Y01511D02*
X06726Y01295D01*
X06663*
Y01787*
X06691Y01815*
X06694Y01814*
X06701Y01815*
X06703Y01817*
X06714*
Y01791*
X06758*
Y01846*
X06768*
Y01791*
X06813*
Y01846*
X0687*
X06874Y01843*
Y01788*
X06919*
Y01843*
X06923Y01846*
X06942*
Y01511*
G37*
G36*
X06791Y01176D02*
X06797D01*
Y01176*
X068*
Y01175*
X06802*
Y01175*
X06803*
Y01174*
X06804*
Y01174*
X06805*
Y01173*
X06807*
Y01173*
X06808*
Y01172*
X06809*
Y01172*
X0681*
Y01171*
X0681*
Y01171*
X06811*
Y0117*
X06812*
Y01169*
X06813*
Y01169*
X06814*
Y01168*
X06814*
Y01168*
X06815*
Y01167*
X06815*
Y01167*
X06816*
Y01166*
X06816*
Y01166*
X06817*
Y01165*
X06817*
Y01165*
X06818*
Y01164*
X06818*
Y01163*
X06819*
Y01163*
Y01162*
X0682*
Y01162*
X0682*
Y01161*
Y01161*
X06821*
Y0116*
X06821*
Y0116*
Y01159*
X06822*
Y01159*
Y01158*
X06822*
Y01158*
X06823*
Y01157*
Y01156*
X06823*
Y01156*
Y01155*
Y01155*
X06824*
Y01154*
Y01154*
X06824*
Y01153*
Y01153*
Y01152*
X06825*
Y01152*
Y01151*
Y01151*
Y0115*
X06825*
Y01149*
Y01149*
Y01148*
Y01148*
X06826*
Y01147*
Y01147*
Y01146*
Y01146*
Y01145*
Y01145*
Y01144*
Y01143*
Y01143*
Y01142*
X06827*
Y01142*
Y01141*
Y01141*
Y0114*
X06826*
Y0114*
Y01139*
Y01139*
Y01138*
Y01138*
Y01137*
Y01136*
Y01136*
Y01135*
X06825*
Y01135*
Y01134*
Y01134*
Y01133*
Y01133*
X06825*
Y01132*
Y01132*
Y01131*
X06824*
Y01131*
Y0113*
Y01129*
X06824*
Y01129*
Y01128*
Y01128*
X06823*
Y01127*
Y01127*
X06823*
Y01126*
Y01126*
X06822*
Y01125*
Y01125*
X06822*
Y01124*
Y01123*
X06821*
Y01123*
Y01122*
X06821*
Y01122*
X0682*
Y01121*
Y01121*
X0682*
Y0112*
X06819*
Y0112*
X06818*
Y01119*
Y01119*
X06818*
Y01118*
X06817*
Y01118*
X06817*
Y01117*
X06816*
Y01116*
X06816*
Y01116*
X06815*
Y01115*
X06815*
Y01115*
X06814*
Y01114*
X06813*
Y01114*
X06813*
Y01113*
X06812*
Y01113*
X06811*
Y01112*
X0681*
Y01112*
X0681*
Y01111*
X06809*
Y01111*
X06808*
Y0111*
X06807*
Y01109*
X06805*
Y01109*
X06804*
Y01108*
X06803*
Y01108*
X06801*
Y01107*
X06799*
Y01107*
X06796*
Y01106*
X06744*
Y01107*
X06741*
Y01107*
X0674*
Y01108*
X06738*
Y01108*
X06736*
Y01109*
X06735*
Y01109*
X06734*
Y0111*
X06733*
Y01111*
X06732*
Y01111*
X06731*
Y01112*
X0673*
Y01112*
X06729*
Y01113*
X06729*
Y01113*
X06728*
Y01114*
X06727*
Y01114*
X06727*
Y01115*
X06726*
Y01115*
X06725*
Y01116*
X06725*
Y01116*
X06724*
Y01117*
X06724*
Y01118*
X06723*
Y01118*
X06723*
Y01119*
X06722*
Y01119*
X06722*
Y0112*
Y0112*
X06721*
Y01121*
X06721*
Y01121*
X0672*
Y01122*
Y01122*
X0672*
Y01123*
Y01123*
X06719*
Y01124*
X06718*
Y01125*
Y01125*
X06718*
Y01126*
Y01126*
X06717*
Y01127*
Y01127*
X06717*
Y01128*
Y01128*
Y01129*
X06716*
Y01129*
Y0113*
Y01131*
X06716*
Y01131*
Y01132*
Y01132*
X06715*
Y01133*
Y01133*
Y01134*
Y01134*
Y01135*
X06715*
Y01135*
Y01136*
Y01136*
Y01137*
Y01138*
X06714*
Y01138*
Y01139*
Y01139*
Y0114*
Y0114*
Y01141*
Y01141*
Y01142*
Y01142*
Y01143*
Y01143*
Y01144*
Y01145*
X06715*
Y01145*
Y01146*
Y01146*
Y01147*
Y01147*
Y01148*
Y01148*
X06715*
Y01149*
Y01149*
Y0115*
Y01151*
X06716*
Y01151*
Y01152*
Y01152*
Y01153*
X06716*
Y01153*
Y01154*
X06717*
Y01154*
Y01155*
Y01155*
X06717*
Y01156*
Y01156*
X06718*
Y01157*
Y01158*
X06718*
Y01158*
Y01159*
X06719*
Y01159*
Y0116*
X0672*
Y0116*
X0672*
Y01161*
Y01161*
X06721*
Y01162*
X06721*
Y01162*
Y01163*
X06722*
Y01163*
X06722*
Y01164*
X06723*
Y01165*
X06723*
Y01165*
X06724*
Y01166*
X06724*
Y01166*
X06725*
Y01167*
X06725*
Y01167*
X06726*
Y01168*
X06727*
Y01168*
X06727*
Y01169*
X06728*
Y01169*
X06728*
Y0117*
X06729*
Y01171*
X0673*
Y01171*
X06731*
Y01172*
X06731*
Y01172*
X06732*
Y01173*
X06734*
Y01173*
X06735*
Y01174*
X06736*
Y01174*
X06737*
Y01175*
X06739*
Y01175*
X06741*
Y01176*
X06743*
Y01176*
X06749*
Y01177*
X0679*
Y01176*
X06791*
Y01177*
X06791*
Y01176*
G37*
G36*
X05972Y0095D02*
X05975D01*
Y0095*
X05976*
Y00949*
X05977*
Y00949*
X05978*
Y00948*
X05979*
Y00948*
X0598*
Y00947*
X0598*
Y00947*
X05982*
Y00946*
X05982*
Y00946*
X05983*
Y00945*
X05983*
Y00945*
X05984*
Y00944*
X05984*
Y00943*
Y00943*
X05985*
Y00942*
X05985*
Y00942*
Y00941*
X05986*
Y00941*
X05986*
Y0094*
Y0094*
X05987*
Y00939*
Y00939*
Y00938*
X05988*
Y00938*
Y00937*
Y00936*
X05988*
Y00936*
Y00935*
Y00935*
Y00934*
X05989*
Y00934*
Y00933*
Y00933*
Y00932*
Y00932*
Y00931*
Y0093*
Y0093*
Y00929*
Y00929*
Y00928*
Y00928*
Y00927*
X05988*
Y00927*
Y00926*
Y00926*
Y00925*
X05988*
Y00925*
Y00924*
Y00923*
X05987*
Y00923*
Y00922*
X05986*
Y00922*
Y00921*
X05986*
Y00921*
Y0092*
X05985*
Y0092*
X05985*
Y00919*
Y00919*
X05984*
Y00918*
X05984*
Y00918*
X05983*
Y00917*
X05983*
Y00916*
X05982*
Y00916*
X05982*
Y00915*
X05981*
Y00915*
X0598*
Y00914*
X05979*
Y00914*
X05979*
Y00913*
X05978*
Y00913*
X05977*
Y00912*
X05975*
Y00912*
X05973*
Y00911*
X0597*
Y0091*
X05966*
Y00911*
X05963*
Y00912*
X05962*
Y00912*
X0596*
Y00913*
X05959*
Y00913*
X05958*
Y00914*
X05957*
Y00914*
X05957*
Y00915*
X05956*
Y00915*
X05955*
Y00916*
X05955*
Y00916*
X05954*
Y00917*
X05953*
Y00918*
X05953*
Y00918*
X05952*
Y00919*
X05952*
Y00919*
Y0092*
X05951*
Y0092*
Y00921*
X05951*
Y00921*
X0595*
Y00922*
Y00922*
X0595*
Y00923*
Y00923*
Y00924*
X05949*
Y00925*
Y00925*
Y00926*
X05949*
Y00926*
Y00927*
Y00927*
Y00928*
Y00928*
X05948*
Y00929*
Y00929*
Y0093*
Y0093*
Y00931*
Y00932*
Y00932*
Y00933*
Y00933*
Y00934*
X05949*
Y00934*
Y00935*
Y00935*
Y00936*
Y00936*
X05949*
Y00937*
Y00938*
Y00938*
X0595*
Y00939*
Y00939*
X0595*
Y0094*
Y0094*
X05951*
Y00941*
Y00941*
X05951*
Y00942*
Y00942*
X05952*
Y00943*
X05952*
Y00943*
X05953*
Y00944*
Y00945*
X05953*
Y00945*
X05954*
Y00946*
X05955*
Y00946*
X05956*
Y00947*
X05956*
Y00947*
X05957*
Y00948*
X05958*
Y00948*
X05958*
Y00949*
X05959*
Y00949*
X05961*
Y0095*
X05962*
Y0095*
X05964*
Y00951*
X05972*
Y0095*
G37*
G36*
X05972Y00877D02*
X05974D01*
Y00877*
X05976*
Y00876*
X05977*
Y00876*
X05978*
Y00875*
X05979*
Y00875*
X0598*
Y00874*
X0598*
Y00874*
X05981*
Y00873*
X05982*
Y00873*
X05983*
Y00872*
X05983*
Y00872*
X05984*
Y00871*
Y0087*
X05984*
Y0087*
X05985*
Y00869*
X05985*
Y00869*
Y00868*
X05986*
Y00868*
Y00867*
X05986*
Y00867*
Y00866*
X05987*
Y00866*
Y00865*
X05988*
Y00865*
Y00864*
Y00863*
X05988*
Y00863*
Y00862*
Y00862*
Y00861*
X05989*
Y00861*
Y0086*
Y0086*
Y00859*
Y00859*
Y00858*
Y00857*
Y00857*
Y00856*
Y00856*
Y00855*
Y00855*
Y00854*
X05988*
Y00854*
Y00853*
Y00853*
Y00852*
X05988*
Y00852*
Y00851*
Y0085*
X05987*
Y0085*
Y00849*
X05986*
Y00849*
Y00848*
X05986*
Y00848*
Y00847*
X05985*
Y00847*
Y00846*
X05985*
Y00846*
X05984*
Y00845*
X05984*
Y00845*
Y00844*
X05983*
Y00843*
X05983*
Y00843*
X05982*
Y00842*
X05981*
Y00842*
X0598*
Y00841*
X0598*
Y00841*
X05979*
Y0084*
X05978*
Y0084*
X05977*
Y00839*
X05976*
Y00839*
X05974*
Y00838*
X05971*
Y00837*
X05965*
Y00838*
X05963*
Y00839*
X05961*
Y00839*
X0596*
Y0084*
X05959*
Y0084*
X05958*
Y00841*
X05957*
Y00841*
X05956*
Y00842*
X05956*
Y00842*
X05955*
Y00843*
X05955*
Y00843*
X05954*
Y00844*
X05953*
Y00845*
X05953*
Y00845*
X05952*
Y00846*
X05952*
Y00846*
Y00847*
X05951*
Y00847*
X05951*
Y00848*
Y00848*
X0595*
Y00849*
Y00849*
X0595*
Y0085*
Y0085*
Y00851*
X05949*
Y00852*
Y00852*
Y00853*
X05949*
Y00853*
Y00854*
Y00854*
Y00855*
X05948*
Y00855*
Y00856*
Y00856*
Y00857*
Y00857*
Y00858*
Y00859*
Y00859*
Y0086*
Y0086*
Y00861*
X05949*
Y00861*
Y00862*
Y00862*
Y00863*
X05949*
Y00863*
Y00864*
Y00865*
Y00865*
X0595*
Y00866*
Y00866*
X0595*
Y00867*
Y00867*
X05951*
Y00868*
Y00868*
X05951*
Y00869*
X05952*
Y00869*
Y0087*
X05952*
Y0087*
X05953*
Y00871*
X05953*
Y00872*
X05954*
Y00872*
X05955*
Y00873*
X05955*
Y00873*
X05956*
Y00874*
X05956*
Y00874*
X05957*
Y00875*
X05958*
Y00875*
X05959*
Y00876*
X0596*
Y00876*
X05961*
Y00877*
X05963*
Y00877*
X05965*
Y00878*
X05972*
Y00877*
G37*
G36*
X06916Y00894D02*
X06919D01*
Y00894*
X06921*
Y00893*
X06923*
Y00893*
X06924*
Y00892*
X06925*
Y00892*
X06927*
Y00891*
X06928*
Y0089*
X06929*
Y0089*
X0693*
Y00889*
X06931*
Y00889*
X06931*
Y00888*
X06933*
Y00888*
X06933*
Y00887*
X06934*
Y00887*
X06934*
Y00886*
X06935*
Y00886*
X06936*
Y00885*
X06936*
Y00885*
X06937*
Y00884*
X06937*
Y00883*
X06938*
Y00883*
X06938*
Y00882*
X06939*
Y00882*
Y00881*
X0694*
Y00881*
X0694*
Y0088*
X06941*
Y0088*
Y00879*
X06941*
Y00879*
X06942*
Y00878*
Y00877*
X06942*
Y00877*
Y00876*
X06943*
Y00876*
X06943*
Y00875*
Y00875*
X06944*
Y00874*
Y00874*
Y00873*
X06944*
Y00873*
Y00872*
X06945*
Y00872*
Y00871*
Y0087*
X06945*
Y0087*
Y00869*
Y00869*
X06946*
Y00868*
Y00868*
Y00867*
Y00867*
X06947*
Y00866*
Y00866*
Y00865*
Y00865*
Y00864*
Y00863*
X06947*
Y00863*
Y00862*
Y00862*
Y00861*
Y00861*
Y0086*
Y0086*
Y00859*
Y00859*
Y00858*
Y00857*
Y00857*
Y00856*
Y00856*
Y00855*
X06947*
Y00855*
Y00854*
Y00854*
Y00853*
Y00853*
Y00852*
X06946*
Y00852*
Y00851*
Y0085*
Y0085*
X06945*
Y00849*
Y00849*
Y00848*
X06945*
Y00848*
Y00847*
Y00847*
X06944*
Y00846*
Y00846*
X06944*
Y00845*
Y00845*
X06943*
Y00844*
Y00843*
X06943*
Y00843*
Y00842*
X06942*
Y00842*
Y00841*
X06942*
Y00841*
X06941*
Y0084*
Y0084*
X06941*
Y00839*
X0694*
Y00839*
Y00838*
X0694*
Y00837*
X06939*
Y00837*
X06938*
Y00836*
X06938*
Y00836*
X06937*
Y00835*
X06937*
Y00835*
X06936*
Y00834*
X06936*
Y00834*
X06935*
Y00833*
X06935*
Y00833*
X06934*
Y00832*
X06934*
Y00832*
X06933*
Y00831*
X06932*
Y0083*
X06931*
Y0083*
X0693*
Y00829*
X06929*
Y00829*
X06929*
Y00828*
X06928*
Y00828*
X06927*
Y00827*
X06925*
Y00827*
X06924*
Y00826*
X06922*
Y00826*
X0692*
Y00825*
X06917*
Y00825*
X06914*
Y00824*
X06914*
Y00825*
X06913*
Y00824*
X06913*
Y00825*
X06912*
Y00824*
X06908*
Y00825*
X06904*
Y00825*
X06902*
Y00826*
X069*
Y00826*
X06898*
Y00827*
X06897*
Y00827*
X06896*
Y00828*
X06895*
Y00828*
X06894*
Y00829*
X06893*
Y00829*
X06892*
Y0083*
X06891*
Y0083*
X0689*
Y00831*
X06889*
Y00832*
X06889*
Y00832*
X06888*
Y00833*
X06888*
Y00833*
X06887*
Y00834*
X06886*
Y00834*
X06885*
Y00835*
X06885*
Y00835*
X06884*
Y00836*
X06884*
Y00836*
Y00837*
X06883*
Y00837*
X06883*
Y00838*
X06882*
Y00839*
X06882*
Y00839*
Y0084*
X06881*
Y0084*
X06881*
Y00841*
Y00841*
X0688*
Y00842*
Y00842*
X0688*
Y00843*
X06879*
Y00843*
Y00844*
X06878*
Y00845*
Y00845*
X06878*
Y00846*
Y00846*
Y00847*
X06877*
Y00847*
Y00848*
X06877*
Y00848*
Y00849*
Y00849*
X06876*
Y0085*
Y0085*
Y00851*
Y00852*
X06876*
Y00852*
Y00853*
Y00853*
Y00854*
Y00854*
X06875*
Y00855*
Y00855*
Y00856*
Y00856*
Y00857*
Y00857*
Y00858*
Y00859*
Y00859*
Y0086*
Y0086*
Y00861*
Y00861*
Y00862*
Y00862*
Y00863*
Y00863*
Y00864*
Y00865*
X06876*
Y00865*
Y00866*
Y00866*
Y00867*
Y00867*
X06876*
Y00868*
Y00868*
Y00869*
Y00869*
X06877*
Y0087*
Y0087*
Y00871*
X06877*
Y00872*
Y00872*
Y00873*
X06878*
Y00873*
Y00874*
X06878*
Y00874*
Y00875*
X06879*
Y00875*
Y00876*
X0688*
Y00876*
Y00877*
X0688*
Y00877*
Y00878*
X06881*
Y00879*
X06881*
Y00879*
Y0088*
X06882*
Y0088*
X06882*
Y00881*
X06883*
Y00881*
Y00882*
X06883*
Y00882*
X06884*
Y00883*
X06884*
Y00883*
X06885*
Y00884*
X06885*
Y00885*
X06886*
Y00885*
X06887*
Y00886*
X06887*
Y00886*
X06888*
Y00887*
X06888*
Y00887*
X06889*
Y00888*
X0689*
Y00888*
X06891*
Y00889*
X06891*
Y00889*
X06893*
Y0089*
X06893*
Y0089*
X06894*
Y00891*
X06895*
Y00892*
X06896*
Y00892*
X06898*
Y00893*
X069*
Y00893*
X06901*
Y00894*
X06903*
Y00894*
X06906*
Y00895*
X06916*
Y00894*
G37*
G36*
X06629Y01176D02*
X06635D01*
Y01176*
X06637*
Y01175*
X06639*
Y01175*
X06641*
Y01174*
X06642*
Y01174*
X06643*
Y01173*
X06644*
Y01173*
X06645*
Y01172*
X06647*
Y01172*
X06648*
Y01171*
X06648*
Y01171*
X06649*
Y0117*
X0665*
Y01169*
X0665*
Y01169*
X06651*
Y01168*
X06652*
Y01168*
X06652*
Y01167*
X06653*
Y01167*
X06654*
Y01166*
X06654*
Y01166*
X06655*
Y01165*
X06655*
Y01165*
X06656*
Y01164*
X06656*
Y01163*
X06657*
Y01163*
Y01162*
X06657*
Y01162*
X06658*
Y01161*
X06658*
Y01161*
Y0116*
X06659*
Y0116*
Y01159*
X0666*
Y01159*
X0666*
Y01158*
Y01158*
X06661*
Y01157*
Y01156*
X06661*
Y01156*
Y01155*
X06662*
Y01155*
Y01154*
Y01154*
X06662*
Y01153*
Y01153*
Y01152*
X06663*
Y01152*
Y01151*
Y01151*
X06663*
Y0115*
Y01149*
Y01149*
Y01148*
X06664*
Y01148*
Y01147*
Y01147*
Y01146*
Y01146*
Y01145*
X06664*
Y01145*
Y01144*
Y01143*
Y01143*
Y01142*
Y01142*
Y01141*
Y01141*
Y0114*
Y0114*
Y01139*
X06664*
Y01139*
X06664*
Y01138*
X06664*
Y01138*
Y01137*
Y01136*
Y01136*
Y01135*
Y01135*
Y01134*
X06663*
Y01134*
Y01133*
Y01133*
Y01132*
X06663*
Y01132*
Y01131*
Y01131*
X06662*
Y0113*
Y01129*
Y01129*
X06662*
Y01128*
Y01128*
Y01127*
X06661*
Y01127*
Y01126*
X06661*
Y01126*
Y01125*
X0666*
Y01125*
Y01124*
X0666*
Y01123*
X06659*
Y01123*
Y01122*
X06658*
Y01122*
X06658*
Y01121*
Y01121*
X06657*
Y0112*
X06657*
Y0112*
X06656*
Y01119*
Y01119*
X06656*
Y01118*
X06655*
Y01118*
X06655*
Y01117*
X06654*
Y01116*
X06654*
Y01116*
X06653*
Y01115*
X06652*
Y01115*
X06652*
Y01114*
X06651*
Y01114*
X0665*
Y01113*
X0665*
Y01113*
X06649*
Y01112*
X06648*
Y01112*
X06647*
Y01111*
X06647*
Y01111*
X06645*
Y0111*
X06644*
Y01109*
X06643*
Y01109*
X06642*
Y01108*
X06641*
Y01108*
X06638*
Y01107*
X06637*
Y01107*
X06634*
Y01106*
X06552*
Y01106*
X06548*
Y01105*
X06545*
Y01105*
X06543*
Y01104*
X06542*
Y01103*
X06541*
Y01103*
X06539*
Y01102*
X06538*
Y01102*
X06537*
Y01101*
X06536*
Y01101*
X06536*
Y011*
X06535*
Y011*
X06534*
Y01099*
X06533*
Y01099*
X06532*
Y01098*
X06532*
Y01098*
X06531*
Y01097*
X0653*
Y01096*
X0653*
Y01096*
X06529*
Y01095*
X06529*
Y01095*
X06528*
Y01094*
X06528*
Y01094*
X06527*
Y01093*
Y01093*
X06527*
Y01092*
X06526*
Y01092*
X06525*
Y01091*
Y01091*
X06525*
Y0109*
X06524*
Y01089*
Y01089*
X06524*
Y01088*
X06523*
Y01088*
Y01087*
X06523*
Y01087*
Y01086*
X06522*
Y01086*
Y01085*
X06522*
Y01085*
Y01084*
Y01083*
X06521*
Y01083*
Y01082*
X06521*
Y01082*
Y01081*
Y01081*
X0652*
Y0108*
Y0108*
Y01079*
Y01079*
X06519*
Y01078*
Y01078*
Y01077*
Y01076*
Y01076*
Y01075*
X06519*
Y01075*
Y01074*
Y01074*
Y01073*
Y01073*
Y01072*
Y01072*
Y01071*
Y0107*
Y0107*
Y01069*
Y01069*
Y01068*
Y01068*
Y01067*
Y01067*
X06519*
Y01066*
Y01066*
Y01065*
Y01065*
Y01064*
Y01063*
X0652*
Y01063*
Y01062*
Y01062*
Y01061*
X06521*
Y01061*
Y0106*
Y0106*
X06521*
Y01059*
Y01059*
Y01058*
X06522*
Y01058*
Y01057*
X06522*
Y01056*
Y01056*
X06523*
Y01055*
Y01055*
X06523*
Y01054*
Y01054*
X06524*
Y01053*
Y01053*
X06524*
Y01052*
X06525*
Y01052*
Y01051*
X06525*
Y0105*
X06526*
Y0105*
Y01049*
X06527*
Y01049*
X06527*
Y01048*
X06528*
Y01048*
X06528*
Y01047*
X06529*
Y01047*
X06529*
Y01046*
X0653*
Y01046*
X0653*
Y01045*
X06531*
Y01045*
X06531*
Y01044*
X06532*
Y01043*
X06532*
Y01043*
X06534*
Y01042*
X06534*
Y01042*
X06535*
Y01041*
X06536*
Y01041*
X06537*
Y0104*
X06538*
Y0104*
X06539*
Y01039*
X0654*
Y01039*
X06541*
Y01038*
X06543*
Y01038*
X06544*
Y01037*
X06547*
Y01036*
X06549*
Y01036*
X06977*
Y01035*
X06977*
Y01036*
X06978*
Y01035*
X06982*
Y01035*
X06984*
Y01034*
X06986*
Y01034*
X06987*
Y01033*
X06989*
Y01033*
X0699*
Y01032*
X06991*
Y01032*
X06992*
Y01031*
X06993*
Y0103*
X06994*
Y0103*
X06995*
Y01029*
X06995*
Y01029*
X06996*
Y01028*
X06997*
Y01028*
X06997*
Y01027*
X06998*
Y01027*
X06999*
Y01026*
X07*
Y01026*
X07*
Y01025*
X07001*
Y01025*
X07001*
Y01024*
X07002*
Y01023*
Y01023*
X07002*
Y01022*
X07003*
Y01022*
X07003*
Y01021*
X07004*
Y01021*
Y0102*
X07004*
Y0102*
X07005*
Y01019*
Y01019*
X07006*
Y01018*
X07006*
Y01018*
Y01017*
X07007*
Y01016*
Y01016*
X07007*
Y01015*
Y01015*
X07008*
Y01014*
Y01014*
Y01013*
X07008*
Y01013*
Y01012*
X07009*
Y01012*
Y01011*
Y0101*
X07009*
Y0101*
Y01009*
Y01009*
Y01008*
X0701*
Y01008*
Y01007*
Y01007*
Y01006*
Y01006*
X0701*
Y01005*
Y01005*
Y01004*
Y01003*
Y01003*
Y01002*
Y01002*
Y01001*
Y01001*
Y01*
Y01*
Y00999*
Y00999*
Y00998*
Y00998*
Y00997*
Y00996*
Y00996*
Y00995*
X0701*
Y00995*
Y00994*
Y00994*
Y00993*
Y00993*
X07009*
Y00992*
Y00992*
Y00991*
Y0099*
X07009*
Y0099*
Y00989*
Y00989*
X07008*
Y00988*
Y00988*
Y00987*
X07008*
Y00987*
Y00986*
X07007*
Y00986*
Y00985*
X07007*
Y00985*
Y00984*
X07006*
Y00983*
Y00983*
X07006*
Y00982*
Y00982*
X07005*
Y00981*
X07004*
Y00981*
Y0098*
X07004*
Y0098*
X07003*
Y00979*
X07003*
Y00979*
X07002*
Y00978*
Y00978*
X07002*
Y00977*
X07001*
Y00976*
X07001*
Y00976*
X07*
Y00975*
X07*
Y00975*
X06999*
Y00974*
X06998*
Y00974*
X06998*
Y00973*
X06997*
Y00973*
X06996*
Y00972*
X06996*
Y00972*
X06995*
Y00971*
X06994*
Y0097*
X06993*
Y0097*
X06992*
Y00969*
X06991*
Y00969*
X0699*
Y00968*
X06989*
Y00968*
X06988*
Y00967*
X06986*
Y00967*
X06984*
Y00966*
X06982*
Y00966*
X06979*
Y00965*
X06698*
Y00965*
X06695*
Y00964*
X06693*
Y00963*
X06691*
Y00963*
X0669*
Y00962*
X06688*
Y00962*
X06687*
Y00961*
X06686*
Y00961*
X06685*
Y0096*
X06684*
Y0096*
X06683*
Y00959*
X06682*
Y00959*
X06682*
Y00958*
X06681*
Y00958*
X0668*
Y00957*
X0668*
Y00956*
X06679*
Y00956*
X06678*
Y00955*
X06678*
Y00955*
X06677*
Y00954*
X06677*
Y00954*
X06676*
Y00953*
X06676*
Y00953*
X06675*
Y00952*
X06675*
Y00952*
X06674*
Y00951*
Y0095*
X06674*
Y0095*
X06673*
Y00949*
Y00949*
X06672*
Y00948*
X06672*
Y00948*
Y00947*
X06671*
Y00947*
Y00946*
X06671*
Y00946*
Y00945*
X0667*
Y00945*
Y00944*
X0667*
Y00943*
Y00943*
X06669*
Y00942*
Y00942*
Y00941*
X06669*
Y00941*
Y0094*
Y0094*
X06668*
Y00939*
Y00939*
Y00938*
Y00938*
X06668*
Y00937*
Y00936*
Y00936*
Y00935*
Y00935*
Y00934*
X06667*
Y00934*
Y00933*
Y00933*
Y00932*
Y00932*
Y00931*
Y0093*
Y0093*
Y00929*
Y00929*
Y00928*
Y00928*
Y00927*
Y00927*
Y00926*
Y00926*
X06668*
Y00925*
Y00925*
Y00924*
Y00923*
Y00923*
Y00922*
X06668*
Y00922*
Y00921*
Y00921*
Y0092*
X06669*
Y0092*
Y00919*
Y00919*
X06669*
Y00918*
Y00918*
Y00917*
X0667*
Y00916*
Y00916*
X0667*
Y00915*
Y00915*
X06671*
Y00914*
Y00914*
X06671*
Y00913*
Y00913*
X06672*
Y00912*
Y00912*
X06672*
Y00911*
X06673*
Y0091*
Y0091*
X06674*
Y00909*
X06674*
Y00909*
X06675*
Y00908*
Y00908*
X06675*
Y00907*
X06676*
Y00907*
X06676*
Y00906*
X06677*
Y00906*
X06677*
Y00905*
X06678*
Y00905*
X06678*
Y00904*
X06679*
Y00903*
X0668*
Y00903*
X06681*
Y00902*
X06681*
Y00902*
X06682*
Y00901*
X06683*
Y00901*
X06683*
Y009*
X06684*
Y009*
X06685*
Y00899*
X06686*
Y00899*
X06687*
Y00898*
X06689*
Y00897*
X0669*
Y00897*
X06691*
Y00896*
X06693*
Y00896*
X06695*
Y00895*
X06699*
Y00895*
X06803*
Y00894*
X06805*
Y00894*
X06808*
Y00893*
X06809*
Y00893*
X06811*
Y00892*
X06813*
Y00892*
X06814*
Y00891*
X06815*
Y0089*
X06816*
Y0089*
X06817*
Y00889*
X06817*
Y00889*
X06818*
Y00888*
X06819*
Y00888*
X0682*
Y00887*
X06821*
Y00887*
X06821*
Y00886*
X06822*
Y00886*
X06822*
Y00885*
X06823*
Y00885*
X06823*
Y00884*
X06824*
Y00883*
X06824*
Y00883*
X06825*
Y00882*
X06825*
Y00882*
X06826*
Y00881*
X06827*
Y00881*
Y0088*
X06827*
Y0088*
X06828*
Y00879*
X06828*
Y00879*
Y00878*
X06829*
Y00877*
Y00877*
X06829*
Y00876*
X0683*
Y00876*
Y00875*
X0683*
Y00875*
Y00874*
X06831*
Y00874*
Y00873*
Y00873*
X06831*
Y00872*
Y00872*
X06832*
Y00871*
Y0087*
Y0087*
X06833*
Y00869*
Y00869*
Y00868*
Y00868*
X06833*
Y00867*
Y00867*
Y00866*
Y00866*
Y00865*
X06834*
Y00865*
Y00864*
Y00863*
Y00863*
Y00862*
Y00862*
Y00861*
Y00861*
Y0086*
Y0086*
Y00859*
Y00859*
Y00858*
Y00857*
Y00857*
Y00856*
Y00856*
Y00855*
Y00855*
Y00854*
Y00854*
X06833*
Y00853*
Y00853*
Y00852*
Y00852*
Y00851*
X06833*
Y0085*
Y0085*
Y00849*
X06832*
Y00849*
Y00848*
Y00848*
X06831*
Y00847*
Y00847*
Y00846*
X06831*
Y00846*
Y00845*
X0683*
Y00845*
Y00844*
X0683*
Y00843*
Y00843*
X06829*
Y00842*
Y00842*
X06829*
Y00841*
Y00841*
X06828*
Y0084*
X06828*
Y0084*
Y00839*
X06827*
Y00839*
X06827*
Y00838*
X06826*
Y00837*
X06825*
Y00837*
Y00836*
X06825*
Y00836*
X06824*
Y00835*
X06824*
Y00835*
X06823*
Y00834*
X06823*
Y00834*
X06822*
Y00833*
X06822*
Y00833*
X06821*
Y00832*
X0682*
Y00832*
X0682*
Y00831*
X06818*
Y0083*
X06818*
Y0083*
X06817*
Y00829*
X06816*
Y00829*
X06815*
Y00828*
X06814*
Y00828*
X06813*
Y00827*
X06812*
Y00827*
X0681*
Y00826*
X06809*
Y00826*
X06807*
Y00825*
X06804*
Y00825*
X06801*
Y00824*
X068*
Y00825*
X06799*
Y00824*
X06637*
Y00825*
X06636*
Y00824*
X06631*
Y00823*
X06628*
Y00823*
X06626*
Y00822*
X06624*
Y00822*
X06623*
Y00821*
X06622*
Y00821*
X06621*
Y0082*
X0662*
Y0082*
X06619*
Y00819*
X06618*
Y00819*
X06617*
Y00818*
X06616*
Y00817*
X06615*
Y00817*
X06615*
Y00816*
X06614*
Y00816*
X06614*
Y00815*
X06612*
Y00815*
X06612*
Y00814*
X06611*
Y00814*
X06611*
Y00813*
X0661*
Y00813*
X0661*
Y00812*
Y00812*
X06609*
Y00811*
X06609*
Y0081*
X06608*
Y0081*
X06608*
Y00809*
Y00809*
X06607*
Y00808*
X06607*
Y00808*
Y00807*
X06606*
Y00807*
X06605*
Y00806*
Y00806*
X06605*
Y00805*
Y00805*
X06604*
Y00804*
Y00803*
X06604*
Y00803*
Y00802*
X06603*
Y00802*
Y00801*
Y00801*
X06603*
Y008*
Y008*
Y00799*
X06602*
Y00799*
Y00798*
Y00797*
X06602*
Y00797*
Y00796*
Y00796*
Y00795*
Y00795*
X06601*
Y00794*
Y00794*
Y00793*
Y00793*
Y00792*
Y00792*
Y00791*
Y0079*
Y0079*
Y00789*
Y00789*
Y00788*
Y00788*
Y00787*
Y00787*
Y00786*
Y00786*
Y00785*
Y00785*
Y00784*
Y00783*
X06602*
Y00783*
Y00782*
Y00782*
Y00781*
Y00781*
X06602*
Y0078*
Y0078*
Y00779*
X06603*
Y00779*
Y00778*
Y00777*
X06603*
Y00777*
Y00776*
Y00776*
X06604*
Y00775*
Y00775*
X06604*
Y00774*
Y00774*
X06605*
Y00773*
Y00773*
X06605*
Y00772*
Y00772*
X06606*
Y00771*
Y0077*
X06607*
Y0077*
X06607*
Y00769*
Y00769*
X06608*
Y00768*
X06608*
Y00768*
X06609*
Y00767*
Y00767*
X06609*
Y00766*
X0661*
Y00766*
X0661*
Y00765*
X06611*
Y00765*
X06611*
Y00764*
X06612*
Y00763*
X06612*
Y00763*
X06613*
Y00762*
X06614*
Y00762*
X06615*
Y00761*
X06615*
Y00761*
X06616*
Y0076*
X06617*
Y0076*
X06617*
Y00759*
X06618*
Y00759*
X0662*
Y00758*
X06621*
Y00757*
X06622*
Y00757*
X06623*
Y00756*
X06624*
Y00756*
X06625*
Y00755*
X06628*
Y00755*
X0663*
Y00754*
X06635*
Y00754*
X06747*
Y00753*
X0675*
Y00753*
X06751*
Y00752*
X06753*
Y00752*
X06755*
Y00751*
X06756*
Y0075*
X06757*
Y0075*
X06758*
Y00749*
X06759*
Y00749*
X0676*
Y00748*
X06761*
Y00748*
X06762*
Y00747*
X06763*
Y00747*
X06763*
Y00746*
X06764*
Y00746*
X06764*
Y00745*
X06765*
Y00745*
X06766*
Y00744*
X06767*
Y00743*
X06767*
Y00743*
X06768*
Y00742*
X06768*
Y00742*
Y00741*
X06769*
Y00741*
X06769*
Y0074*
X0677*
Y0074*
X0677*
Y00739*
Y00739*
X06771*
Y00738*
X06771*
Y00737*
Y00737*
X06772*
Y00736*
X06772*
Y00736*
Y00735*
X06773*
Y00735*
Y00734*
X06774*
Y00734*
Y00733*
X06774*
Y00733*
Y00732*
X06775*
Y00732*
Y00731*
Y0073*
X06775*
Y0073*
Y00729*
Y00729*
X06776*
Y00728*
Y00728*
Y00727*
X06776*
Y00727*
Y00726*
Y00726*
Y00725*
Y00725*
Y00724*
X06777*
Y00723*
Y00723*
Y00722*
Y00722*
Y00721*
Y00721*
Y0072*
Y0072*
Y00719*
X06777*
Y00719*
Y00718*
X06777*
Y00717*
Y00717*
Y00716*
Y00716*
Y00715*
Y00715*
Y00714*
Y00714*
Y00713*
Y00713*
X06776*
Y00712*
Y00712*
Y00711*
Y0071*
Y0071*
X06776*
Y00709*
Y00709*
Y00708*
X06775*
Y00708*
Y00707*
Y00707*
X06775*
Y00706*
Y00706*
Y00705*
X06774*
Y00704*
Y00704*
Y00703*
X06774*
Y00703*
Y00702*
X06773*
Y00702*
Y00701*
X06772*
Y00701*
Y007*
X06772*
Y007*
X06771*
Y00699*
Y00699*
X06771*
Y00698*
X0677*
Y00697*
Y00697*
X0677*
Y00696*
X06769*
Y00696*
X06769*
Y00695*
Y00695*
X06768*
Y00694*
X06768*
Y00694*
X06767*
Y00693*
X06767*
Y00693*
X06766*
Y00692*
X06765*
Y00692*
X06765*
Y00691*
X06764*
Y0069*
X06764*
Y0069*
X06763*
Y00689*
X06762*
Y00689*
X06762*
Y00688*
X06761*
Y00688*
X0676*
Y00687*
X0676*
Y00687*
X06758*
Y00686*
X06757*
Y00686*
X06756*
Y00685*
X06755*
Y00684*
X06754*
Y00684*
X06751*
Y00683*
X06362*
Y00683*
X06361*
Y00682*
X06361*
Y00682*
X0636*
Y00681*
X06359*
Y00681*
Y0068*
X06359*
Y0068*
Y00679*
Y00679*
Y00678*
Y00677*
Y00677*
Y00676*
Y00676*
Y00675*
Y00675*
Y00674*
Y00674*
Y00673*
Y00673*
Y00672*
Y00672*
Y00671*
Y0067*
Y0067*
Y00669*
Y00669*
Y00668*
Y00668*
Y00667*
Y00667*
Y00666*
Y00666*
Y00665*
Y00664*
Y00664*
Y00663*
Y00663*
Y00662*
Y00662*
Y00661*
Y00661*
Y0066*
Y0066*
Y00659*
Y00659*
Y00658*
Y00657*
Y00657*
Y00656*
Y00656*
Y00655*
Y00655*
Y00654*
Y00654*
Y00653*
Y00653*
Y00652*
Y00652*
Y00651*
Y0065*
Y0065*
Y00649*
Y00649*
Y00648*
Y00648*
Y00647*
Y00647*
Y00646*
Y00646*
Y00645*
Y00644*
Y00644*
Y00643*
Y00643*
Y00642*
Y00642*
Y00641*
Y00641*
Y0064*
Y0064*
Y00639*
Y00639*
Y00638*
Y00637*
Y00637*
Y00636*
Y00636*
Y00635*
Y00635*
Y00634*
Y00634*
Y00633*
Y00633*
Y00632*
Y00632*
Y00631*
Y0063*
Y0063*
Y00629*
Y00629*
Y00628*
Y00628*
Y00627*
Y00627*
X06358*
Y00626*
Y00626*
X06358*
Y00625*
Y00624*
X06357*
Y00624*
X06356*
Y00623*
X06355*
Y00623*
X06252*
Y00623*
X0625*
Y00624*
X0625*
Y00624*
X06249*
Y00625*
X06249*
Y00626*
Y00626*
X06248*
Y00627*
Y00627*
Y00628*
Y00628*
Y00629*
Y00629*
Y0063*
Y0063*
Y00631*
Y00632*
Y00632*
Y00633*
Y00633*
Y00634*
Y00634*
Y00635*
Y00635*
Y00636*
Y00636*
Y00637*
Y00637*
Y00638*
Y00639*
Y00639*
Y0064*
Y0064*
Y00641*
Y00641*
Y00642*
Y00642*
Y00643*
Y00643*
Y00644*
Y00644*
Y00645*
Y00646*
Y00646*
Y00647*
Y00647*
Y00648*
Y00648*
Y00649*
Y00649*
Y0065*
Y0065*
Y00651*
Y00652*
Y00652*
Y00653*
Y00653*
Y00654*
Y00654*
Y00655*
Y00655*
Y00656*
Y00656*
Y00657*
Y00657*
Y00658*
Y00659*
Y00659*
X06248*
Y0066*
Y0066*
Y00661*
X06247*
Y00661*
Y00662*
X06246*
Y00662*
X06245*
Y00663*
X06244*
Y00663*
X06242*
Y00663*
X06241*
Y00662*
X0624*
Y00662*
X06239*
Y00661*
X06239*
Y00661*
X06238*
Y0066*
Y0066*
Y00659*
Y00659*
X06238*
Y00658*
Y00657*
Y00657*
Y00656*
Y00656*
Y00655*
Y00655*
Y00654*
Y00654*
Y00653*
Y00653*
Y00652*
Y00652*
Y00651*
Y0065*
Y0065*
Y00649*
Y00649*
Y00648*
Y00648*
Y00647*
Y00647*
Y00646*
Y00646*
Y00645*
Y00644*
Y00644*
Y00643*
Y00643*
Y00642*
Y00642*
Y00641*
Y00641*
Y0064*
Y0064*
Y00639*
Y00639*
Y00638*
Y00637*
Y00637*
Y00636*
Y00636*
Y00635*
Y00635*
Y00634*
Y00634*
Y00633*
Y00633*
Y00632*
Y00632*
Y00631*
Y0063*
Y0063*
Y00629*
Y00629*
Y00628*
Y00628*
Y00627*
Y00627*
Y00626*
Y00626*
X06237*
Y00625*
X06237*
Y00624*
X06236*
Y00624*
X06236*
Y00623*
X06234*
Y00623*
X06181*
Y00623*
X0618*
Y00624*
X06179*
Y00624*
X06178*
Y00625*
Y00626*
X06178*
Y00626*
Y00627*
Y00627*
X06177*
Y00628*
Y00628*
Y00629*
Y00629*
Y0063*
Y0063*
Y00631*
Y00632*
Y00632*
Y00633*
Y00633*
Y00634*
Y00634*
Y00635*
Y00635*
Y00636*
Y00636*
Y00637*
Y00637*
Y00638*
Y00639*
Y00639*
Y0064*
Y0064*
Y00641*
Y00641*
Y00642*
Y00642*
Y00643*
Y00643*
Y00644*
Y00644*
Y00645*
Y00646*
Y00646*
Y00647*
Y00647*
Y00648*
Y00648*
Y00649*
Y00649*
Y0065*
Y0065*
Y00651*
Y00652*
Y00652*
Y00653*
Y00653*
Y00654*
Y00654*
Y00655*
Y00655*
Y00656*
Y00656*
Y00657*
Y00657*
Y00658*
Y00659*
Y00659*
Y0066*
Y0066*
Y00661*
Y00661*
Y00662*
Y00662*
Y00663*
Y00663*
Y00664*
Y00664*
Y00665*
Y00666*
Y00666*
Y00667*
Y00667*
Y00668*
Y00668*
Y00669*
Y00669*
Y0067*
Y0067*
Y00671*
X06178*
Y00672*
X06177*
Y00672*
Y00673*
Y00673*
Y00674*
Y00674*
Y00675*
Y00675*
Y00676*
Y00676*
X06177*
Y00677*
Y00677*
X06176*
Y00678*
Y00679*
X06176*
Y00679*
Y0068*
X06175*
Y0068*
X06175*
Y00681*
X06174*
Y00681*
X06173*
Y00682*
X06172*
Y00682*
X06171*
Y00683*
X0617*
Y00683*
X06165*
Y00683*
X06164*
Y00682*
X06163*
Y00682*
X06162*
Y00681*
X06161*
Y00681*
X06161*
Y0068*
X0616*
Y0068*
X06159*
Y00679*
X06159*
Y00679*
Y00678*
X06158*
Y00677*
Y00677*
X06158*
Y00676*
Y00676*
Y00675*
Y00675*
Y00674*
Y00674*
X06157*
Y00673*
X06158*
Y00673*
Y00672*
X06157*
Y00672*
X06158*
Y00671*
Y0067*
Y0067*
Y00669*
Y00669*
Y00668*
Y00668*
Y00667*
Y00667*
Y00666*
Y00666*
Y00665*
Y00664*
Y00664*
Y00663*
Y00663*
Y00662*
Y00662*
Y00661*
Y00661*
Y0066*
Y0066*
Y00659*
Y00659*
Y00658*
Y00657*
Y00657*
Y00656*
Y00656*
Y00655*
Y00655*
Y00654*
Y00654*
Y00653*
Y00653*
Y00652*
Y00652*
Y00651*
Y0065*
Y0065*
Y00649*
Y00649*
Y00648*
X06157*
Y00648*
Y00647*
Y00647*
Y00646*
X06157*
Y00646*
X06156*
Y00645*
X06156*
Y00644*
X06155*
Y00644*
X06153*
Y00643*
X06121*
Y00644*
X06119*
Y00644*
X06119*
Y00645*
X06118*
Y00646*
X06118*
Y00646*
X06117*
Y00647*
Y00647*
Y00648*
X06117*
Y00648*
Y00649*
Y00649*
Y0065*
Y0065*
Y00651*
Y00652*
Y00652*
Y00653*
Y00653*
Y00654*
Y00654*
Y00655*
Y00655*
Y00656*
Y00656*
Y00657*
Y00657*
Y00658*
Y00659*
Y00659*
Y0066*
Y0066*
Y00661*
Y00661*
Y00662*
Y00662*
Y00663*
Y00663*
Y00664*
Y00664*
Y00665*
Y00666*
Y00666*
Y00667*
Y00667*
Y00668*
Y00668*
Y00669*
Y00669*
Y0067*
Y0067*
Y00671*
Y00672*
Y00672*
Y00673*
Y00673*
Y00674*
Y00674*
Y00675*
Y00675*
X06117*
Y00676*
Y00676*
X06117*
Y00677*
X06117*
Y00677*
X06117*
Y00678*
Y00679*
Y00679*
Y0068*
Y0068*
Y00681*
X06116*
Y00681*
Y00682*
X06116*
Y00682*
X06115*
Y00683*
X06113*
Y00683*
X0603*
Y00683*
X06029*
Y00682*
X06028*
Y00682*
X06028*
Y00681*
X06027*
Y00681*
Y0068*
X06026*
Y0068*
Y00679*
Y00679*
Y00678*
Y00677*
Y00677*
Y00676*
Y00676*
Y00675*
Y00675*
Y00674*
Y00674*
Y00673*
Y00673*
Y00672*
Y00672*
Y00671*
Y0067*
Y0067*
Y00669*
Y00669*
Y00668*
Y00668*
Y00667*
Y00667*
Y00666*
Y00666*
Y00665*
Y00664*
Y00664*
Y00663*
Y00663*
Y00662*
Y00662*
Y00661*
Y00661*
Y0066*
Y0066*
Y00659*
Y00659*
Y00658*
Y00657*
Y00657*
Y00656*
Y00656*
Y00655*
Y00655*
Y00654*
Y00654*
Y00653*
Y00653*
Y00652*
Y00652*
Y00651*
Y0065*
Y0065*
Y00649*
Y00649*
Y00648*
Y00648*
Y00647*
Y00647*
Y00646*
Y00646*
Y00645*
Y00644*
Y00644*
Y00643*
Y00643*
Y00642*
Y00642*
Y00641*
Y00641*
Y0064*
Y0064*
Y00639*
Y00639*
Y00638*
Y00637*
Y00637*
Y00636*
Y00636*
Y00635*
Y00635*
Y00634*
Y00634*
Y00633*
X05946*
Y00634*
Y00634*
Y00635*
Y00635*
Y00636*
Y00636*
Y00637*
Y00637*
Y00638*
Y00639*
Y00639*
Y0064*
Y0064*
Y00641*
Y00641*
Y00642*
Y00642*
Y00643*
Y00643*
Y00644*
Y00644*
Y00645*
Y00646*
Y00646*
Y00647*
Y00647*
Y00648*
Y00648*
Y00649*
Y00649*
Y0065*
Y0065*
Y00651*
Y00652*
Y00652*
Y00653*
Y00653*
Y00654*
Y00654*
Y00655*
Y00655*
Y00656*
Y00656*
Y00657*
Y00657*
Y00658*
Y00659*
Y00659*
Y0066*
Y0066*
Y00661*
Y00661*
Y00662*
Y00662*
Y00663*
Y00663*
Y00664*
Y00664*
Y00665*
Y00666*
Y00666*
Y00667*
Y00667*
Y00668*
Y00668*
Y00669*
Y00669*
Y0067*
Y0067*
Y00671*
Y00672*
Y00672*
Y00673*
Y00673*
Y00674*
Y00674*
Y00675*
Y00675*
Y00676*
Y00676*
Y00677*
Y00677*
Y00678*
Y00679*
Y00679*
Y0068*
Y0068*
Y00681*
Y00681*
Y00682*
X05998*
Y00682*
Y00683*
Y00683*
Y00684*
Y00684*
Y00685*
Y00686*
Y00686*
Y00687*
Y00687*
Y00688*
Y00688*
Y00689*
Y00689*
Y0069*
Y0069*
Y00691*
Y00692*
Y00692*
Y00693*
Y00693*
Y00694*
Y00694*
Y00695*
Y00695*
Y00696*
Y00696*
Y00697*
Y00697*
Y00698*
Y00699*
Y00699*
Y007*
Y007*
Y00701*
Y00701*
Y00702*
Y00702*
Y00703*
Y00703*
Y00704*
Y00704*
Y00705*
Y00706*
Y00706*
Y00707*
Y00707*
Y00708*
Y00708*
Y00709*
Y00709*
Y0071*
Y0071*
Y00711*
Y00712*
Y00712*
Y00713*
Y00713*
Y00714*
Y00714*
Y00715*
Y00715*
Y00716*
Y00716*
Y00717*
Y00717*
Y00718*
Y00719*
Y00719*
Y0072*
Y0072*
Y00721*
Y00721*
Y00722*
Y00722*
Y00723*
Y00723*
Y00724*
Y00725*
Y00725*
Y00726*
Y00726*
Y00727*
Y00727*
Y00728*
Y00728*
Y00729*
Y00729*
Y0073*
Y0073*
Y00731*
Y00732*
Y00732*
Y00733*
Y00733*
Y00734*
Y00734*
Y00735*
Y00735*
Y00736*
Y00736*
Y00737*
Y00737*
Y00738*
Y00739*
Y00739*
Y0074*
Y0074*
Y00741*
Y00741*
X05946*
Y00742*
Y00742*
Y00743*
Y00743*
Y00744*
Y00745*
Y00745*
Y00746*
Y00746*
Y00747*
Y00747*
Y00748*
Y00748*
Y00749*
Y00749*
Y0075*
Y0075*
Y00751*
Y00752*
Y00752*
Y00753*
Y00753*
Y00754*
Y00754*
Y00755*
X05998*
Y00755*
Y00756*
Y00756*
Y00757*
Y00757*
Y00758*
Y00759*
Y00759*
Y0076*
Y0076*
Y00761*
Y00761*
Y00762*
Y00762*
Y00763*
Y00763*
Y00764*
Y00765*
Y00765*
Y00766*
Y00766*
Y00767*
Y00767*
Y00768*
Y00768*
Y00769*
Y00769*
Y0077*
Y0077*
Y00771*
Y00772*
Y00772*
Y00773*
Y00773*
Y00774*
Y00774*
Y00775*
Y00775*
Y00776*
Y00776*
Y00777*
Y00777*
Y00778*
Y00779*
Y00779*
Y0078*
Y0078*
Y00781*
Y00781*
Y00782*
Y00782*
Y00783*
Y00783*
Y00784*
Y00785*
Y00785*
Y00786*
Y00786*
Y00787*
Y00787*
Y00788*
Y00788*
Y00789*
Y00789*
Y0079*
Y0079*
Y00791*
Y00792*
Y00792*
Y00793*
Y00793*
Y00794*
Y00794*
Y00795*
Y00795*
Y00796*
Y00796*
Y00797*
Y00797*
Y00798*
Y00799*
Y00799*
Y008*
Y008*
Y00801*
Y00801*
Y00802*
Y00802*
Y00803*
Y00803*
Y00804*
Y00805*
Y00805*
Y00806*
Y00806*
Y00807*
Y00807*
Y00808*
Y00808*
Y00809*
Y00809*
Y0081*
Y0081*
Y00811*
Y00812*
Y00812*
Y00813*
Y00813*
Y00814*
Y00814*
X05946*
Y00815*
X05946*
Y00815*
Y00816*
Y00816*
Y00817*
Y00817*
Y00818*
Y00819*
Y00819*
Y0082*
Y0082*
Y00821*
Y00821*
Y00822*
Y00822*
Y00823*
Y00823*
Y00824*
Y00825*
Y00825*
Y00826*
Y00826*
Y00827*
Y00827*
Y00828*
X05998*
Y00828*
Y00829*
Y00829*
Y0083*
Y0083*
Y00831*
Y00832*
Y00832*
Y00833*
Y00833*
Y00834*
Y00834*
Y00835*
Y00835*
Y00836*
Y00836*
Y00837*
Y00837*
Y00838*
Y00839*
Y00839*
Y0084*
Y0084*
Y00841*
Y00841*
Y00842*
Y00842*
Y00843*
Y00843*
Y00844*
Y00845*
Y00845*
Y00846*
Y00846*
Y00847*
Y00847*
Y00848*
Y00848*
Y00849*
Y00849*
Y0085*
Y0085*
Y00851*
Y00852*
Y00852*
Y00853*
Y00853*
Y00854*
Y00854*
Y00855*
Y00855*
Y00856*
Y00856*
Y00857*
Y00857*
Y00858*
Y00859*
Y00859*
Y0086*
Y0086*
Y00861*
Y00861*
Y00862*
Y00862*
Y00863*
Y00863*
Y00864*
Y00865*
Y00865*
Y00866*
Y00866*
Y00867*
Y00867*
Y00868*
Y00868*
Y00869*
Y00869*
Y0087*
Y0087*
Y00871*
Y00872*
Y00872*
Y00873*
Y00873*
Y00874*
Y00874*
Y00875*
Y00875*
Y00876*
Y00876*
Y00877*
Y00877*
Y00878*
Y00879*
Y00879*
Y0088*
Y0088*
Y00881*
Y00881*
Y00882*
Y00882*
Y00883*
Y00883*
Y00884*
Y00885*
Y00885*
Y00886*
Y00886*
Y00887*
Y00887*
Y00888*
X05946*
Y00888*
Y00889*
Y00889*
Y0089*
Y0089*
Y00891*
Y00892*
Y00892*
Y00893*
Y00893*
Y00894*
Y00894*
Y00895*
Y00895*
Y00896*
Y00896*
Y00897*
Y00897*
Y00898*
Y00899*
Y00899*
Y009*
Y009*
Y00901*
X05946*
Y00901*
X05998*
Y00902*
Y00902*
Y00903*
Y00903*
Y00904*
Y00905*
Y00905*
Y00906*
Y00906*
Y00907*
Y00907*
Y00908*
Y00908*
Y00909*
Y00909*
Y0091*
Y0091*
Y00911*
Y00912*
Y00912*
Y00913*
Y00913*
Y00914*
Y00914*
Y00915*
Y00915*
Y00916*
Y00916*
Y00917*
Y00918*
Y00918*
Y00919*
Y00919*
Y0092*
Y0092*
Y00921*
Y00921*
Y00922*
Y00922*
Y00923*
Y00923*
Y00924*
Y00925*
Y00925*
Y00926*
Y00926*
Y00927*
Y00927*
Y00928*
Y00928*
Y00929*
Y00929*
Y0093*
Y0093*
Y00931*
Y00932*
Y00932*
Y00933*
Y00933*
Y00934*
Y00934*
Y00935*
Y00935*
Y00936*
Y00936*
Y00937*
Y00938*
Y00938*
Y00939*
Y00939*
Y0094*
Y0094*
Y00941*
Y00941*
Y00942*
Y00942*
Y00943*
Y00943*
Y00944*
Y00945*
Y00945*
Y00946*
Y00946*
Y00947*
Y00947*
Y00948*
Y00948*
Y00949*
Y00949*
Y0095*
Y0095*
Y00951*
Y00952*
Y00952*
Y00953*
Y00953*
Y00954*
Y00954*
Y00955*
Y00955*
Y00956*
Y00956*
Y00957*
Y00958*
Y00958*
Y00959*
Y00959*
Y0096*
Y0096*
Y00961*
X05946*
Y00961*
Y00962*
Y00962*
Y00963*
Y00963*
Y00964*
Y00965*
Y00965*
Y00966*
Y00966*
Y00967*
Y00967*
Y00968*
Y00968*
Y00969*
Y00969*
Y0097*
Y0097*
Y00971*
Y00972*
Y00972*
Y00973*
Y00973*
Y00974*
Y00974*
Y00975*
Y00975*
Y00976*
Y00976*
Y00977*
Y00978*
Y00978*
Y00979*
Y00979*
Y0098*
Y0098*
Y00981*
Y00981*
Y00982*
Y00982*
Y00983*
Y00983*
Y00984*
Y00985*
Y00985*
Y00986*
Y00986*
Y00987*
Y00987*
Y00988*
Y00988*
Y00989*
Y00989*
Y0099*
Y0099*
Y00991*
Y00992*
Y00992*
Y00993*
Y00993*
Y00994*
Y00994*
Y00995*
Y00995*
Y00996*
Y00996*
Y00997*
Y00998*
Y00998*
Y00999*
Y00999*
Y01*
Y01*
Y01001*
Y01001*
Y01002*
Y01002*
Y01003*
Y01003*
Y01004*
Y01005*
Y01005*
Y01006*
Y01006*
Y01007*
Y01007*
Y01008*
Y01008*
Y01009*
Y01009*
Y0101*
Y0101*
Y01011*
Y01012*
Y01012*
Y01013*
Y01013*
Y01014*
Y01014*
Y01015*
Y01015*
Y01016*
Y01016*
Y01017*
Y01018*
Y01018*
Y01019*
Y01019*
Y0102*
Y0102*
Y01021*
Y01021*
Y01022*
Y01022*
Y01023*
Y01023*
Y01024*
Y01025*
Y01025*
Y01026*
Y01026*
Y01027*
Y01027*
Y01028*
Y01028*
Y01029*
Y01029*
Y0103*
Y0103*
Y01031*
Y01032*
Y01032*
Y01033*
Y01033*
Y01034*
Y01034*
Y01035*
Y01035*
Y01036*
Y01036*
Y01037*
Y01038*
Y01038*
Y01039*
Y01039*
Y0104*
Y0104*
Y01041*
Y01041*
Y01042*
Y01042*
Y01043*
Y01043*
Y01044*
Y01045*
Y01045*
Y01046*
Y01046*
Y01047*
Y01047*
Y01048*
Y01048*
Y01049*
Y01049*
Y0105*
Y0105*
Y01051*
Y01052*
Y01052*
Y01053*
Y01053*
Y01054*
Y01054*
Y01055*
Y01055*
Y01056*
Y01056*
Y01057*
Y01058*
Y01058*
Y01059*
Y01059*
Y0106*
Y0106*
Y01061*
Y01061*
Y01062*
Y01062*
Y01063*
Y01063*
Y01064*
Y01065*
Y01065*
Y01066*
Y01066*
Y01067*
Y01067*
Y01068*
Y01068*
Y01069*
Y01069*
Y0107*
Y0107*
Y01071*
Y01072*
Y01072*
Y01073*
Y01073*
Y01074*
Y01074*
Y01075*
Y01075*
Y01076*
Y01076*
Y01077*
Y01078*
Y01078*
Y01079*
Y01079*
Y0108*
Y0108*
Y01081*
Y01081*
Y01082*
Y01082*
Y01083*
Y01083*
Y01084*
Y01085*
Y01085*
Y01086*
Y01086*
Y01087*
Y01087*
Y01088*
Y01088*
Y01089*
Y01089*
Y0109*
Y01091*
Y01091*
Y01092*
Y01092*
Y01093*
Y01093*
Y01094*
Y01094*
Y01095*
Y01095*
Y01096*
Y01096*
Y01097*
Y01098*
Y01098*
Y01099*
Y01099*
Y011*
Y011*
Y01101*
Y01101*
Y01102*
Y01102*
Y01103*
Y01103*
Y01104*
Y01105*
Y01105*
Y01106*
Y01106*
Y01107*
Y01107*
Y01108*
Y01108*
Y01109*
Y01109*
Y0111*
Y01111*
Y01111*
Y01112*
Y01112*
Y01113*
Y01113*
Y01114*
Y01114*
Y01115*
Y01115*
Y01116*
Y01116*
Y01117*
Y01118*
Y01118*
Y01119*
Y01119*
Y0112*
Y0112*
Y01121*
Y01121*
Y01122*
Y01122*
Y01123*
Y01123*
Y01124*
Y01125*
Y01125*
Y01126*
Y01126*
Y01127*
Y01127*
Y01128*
Y01128*
Y01129*
Y01129*
Y0113*
Y01131*
Y01131*
Y01132*
Y01132*
Y01133*
Y01133*
Y01134*
Y01134*
Y01135*
Y01135*
Y01136*
Y01136*
Y01137*
Y01138*
Y01138*
Y01139*
Y01139*
Y0114*
Y0114*
Y01141*
Y01141*
Y01142*
Y01142*
Y01143*
Y01143*
Y01144*
Y01145*
Y01145*
Y01146*
Y01146*
Y01147*
Y01147*
Y01148*
Y01148*
Y01149*
Y01149*
Y0115*
Y01151*
Y01151*
Y01152*
Y01152*
Y01153*
Y01153*
Y01154*
Y01154*
Y01155*
Y01155*
Y01156*
Y01156*
Y01157*
Y01158*
Y01158*
Y01159*
Y01159*
Y0116*
Y0116*
Y01161*
Y01161*
Y01162*
Y01162*
Y01163*
Y01163*
Y01164*
Y01165*
Y01165*
Y01166*
Y01166*
Y01167*
Y01167*
Y01168*
Y01168*
Y01169*
Y01169*
Y0117*
Y01171*
Y01171*
Y01172*
Y01172*
Y01173*
Y01173*
Y01174*
Y01174*
Y01175*
Y01175*
Y01176*
Y01176*
X05946*
Y01177*
X06629*
Y01176*
G37*
G36*
X05971Y00805D02*
X05973D01*
Y00804*
X05975*
Y00803*
X05977*
Y00803*
X05978*
Y00802*
X05979*
Y00802*
X05979*
Y00801*
X0598*
Y00801*
X05981*
Y008*
X05982*
Y008*
X05982*
Y00799*
X05983*
Y00799*
X05983*
Y00798*
X05984*
Y00797*
X05984*
Y00797*
X05985*
Y00796*
Y00796*
X05985*
Y00795*
X05986*
Y00795*
Y00794*
X05986*
Y00794*
Y00793*
X05987*
Y00793*
Y00792*
X05988*
Y00792*
Y00791*
Y0079*
X05988*
Y0079*
Y00789*
Y00789*
Y00788*
X05989*
Y00788*
Y00787*
Y00787*
Y00786*
Y00786*
Y00785*
Y00785*
Y00784*
Y00783*
Y00783*
Y00782*
Y00782*
Y00781*
X05988*
Y00781*
Y0078*
Y0078*
Y00779*
X05988*
Y00779*
Y00778*
Y00777*
X05987*
Y00777*
Y00776*
Y00776*
X05986*
Y00775*
Y00775*
X05986*
Y00774*
X05985*
Y00774*
Y00773*
X05985*
Y00773*
X05984*
Y00772*
Y00772*
X05984*
Y00771*
X05983*
Y0077*
X05983*
Y0077*
X05982*
Y00769*
X05982*
Y00769*
X0598*
Y00768*
X0598*
Y00768*
X05979*
Y00767*
X05978*
Y00767*
X05977*
Y00766*
X05976*
Y00766*
X05975*
Y00765*
X05972*
Y00765*
X05964*
Y00765*
X05963*
Y00766*
X05961*
Y00766*
X05959*
Y00767*
X05959*
Y00767*
X05958*
Y00768*
X05957*
Y00768*
X05956*
Y00769*
X05956*
Y00769*
X05955*
Y0077*
X05954*
Y0077*
X05953*
Y00771*
X05953*
Y00772*
Y00772*
X05952*
Y00773*
X05952*
Y00773*
X05951*
Y00774*
Y00774*
X05951*
Y00775*
Y00775*
X0595*
Y00776*
Y00776*
X0595*
Y00777*
Y00777*
X05949*
Y00778*
Y00779*
Y00779*
X05949*
Y0078*
Y0078*
Y00781*
Y00781*
Y00782*
X05948*
Y00782*
Y00783*
Y00783*
Y00784*
Y00785*
Y00785*
Y00786*
Y00786*
Y00787*
Y00787*
X05949*
Y00788*
Y00788*
Y00789*
Y00789*
Y0079*
X05949*
Y0079*
Y00791*
Y00792*
X0595*
Y00792*
Y00793*
Y00793*
X0595*
Y00794*
Y00794*
X05951*
Y00795*
Y00795*
X05951*
Y00796*
X05952*
Y00796*
Y00797*
X05952*
Y00797*
X05953*
Y00798*
X05953*
Y00799*
X05954*
Y00799*
X05955*
Y008*
X05955*
Y008*
X05956*
Y00801*
X05956*
Y00801*
X05957*
Y00802*
X05958*
Y00802*
X05959*
Y00803*
X0596*
Y00803*
X05962*
Y00804*
X05963*
Y00805*
X05966*
Y00805*
X05971*
Y00805*
G37*
G36*
X05973Y00731D02*
X05975D01*
Y0073*
X05976*
Y0073*
X05977*
Y00729*
X05978*
Y00729*
X05979*
Y00728*
X0598*
Y00728*
X05981*
Y00727*
X05982*
Y00727*
X05982*
Y00726*
X05983*
Y00726*
X05983*
Y00725*
X05984*
Y00725*
X05984*
Y00724*
X05985*
Y00723*
Y00723*
X05985*
Y00722*
X05986*
Y00722*
Y00721*
X05986*
Y00721*
Y0072*
X05987*
Y0072*
Y00719*
X05988*
Y00719*
Y00718*
Y00717*
X05988*
Y00717*
Y00716*
Y00716*
Y00715*
Y00715*
X05989*
Y00714*
Y00714*
Y00713*
Y00713*
Y00712*
Y00712*
Y00711*
Y0071*
Y0071*
Y00709*
Y00709*
Y00708*
X05988*
Y00708*
Y00707*
Y00707*
Y00706*
Y00706*
X05988*
Y00705*
Y00704*
Y00704*
X05987*
Y00703*
Y00703*
X05986*
Y00702*
Y00702*
X05986*
Y00701*
Y00701*
X05985*
Y007*
X05985*
Y007*
Y00699*
X05984*
Y00699*
X05984*
Y00698*
X05983*
Y00697*
X05983*
Y00697*
X05982*
Y00696*
X05982*
Y00696*
X05981*
Y00695*
X0598*
Y00695*
X05979*
Y00694*
X05978*
Y00694*
X05977*
Y00693*
X05976*
Y00693*
X05975*
Y00692*
X05973*
Y00692*
X05964*
Y00692*
X05962*
Y00693*
X0596*
Y00693*
X05959*
Y00694*
X05958*
Y00694*
X05957*
Y00695*
X05957*
Y00695*
X05956*
Y00696*
X05955*
Y00696*
X05955*
Y00697*
X05954*
Y00697*
X05953*
Y00698*
X05953*
Y00699*
X05952*
Y00699*
Y007*
X05952*
Y007*
X05951*
Y00701*
Y00701*
X05951*
Y00702*
Y00702*
X0595*
Y00703*
Y00703*
X0595*
Y00704*
Y00704*
X05949*
Y00705*
Y00706*
Y00706*
X05949*
Y00707*
Y00707*
Y00708*
Y00708*
Y00709*
X05948*
Y00709*
Y0071*
Y0071*
Y00711*
Y00712*
Y00712*
Y00713*
Y00713*
Y00714*
Y00714*
X05949*
Y00715*
Y00715*
Y00716*
Y00716*
Y00717*
X05949*
Y00717*
Y00718*
Y00719*
X0595*
Y00719*
Y0072*
X0595*
Y0072*
Y00721*
X05951*
Y00721*
Y00722*
X05951*
Y00722*
Y00723*
X05952*
Y00723*
X05952*
Y00724*
Y00725*
X05953*
Y00725*
X05953*
Y00726*
X05954*
Y00726*
X05955*
Y00727*
X05955*
Y00727*
X05956*
Y00728*
X05957*
Y00728*
X05957*
Y00729*
X05958*
Y00729*
X05959*
Y0073*
X0596*
Y0073*
X05962*
Y00731*
X05964*
Y00732*
X05973*
Y00731*
G37*
G36*
X05894Y01176D02*
X05899D01*
Y01176*
X05902*
Y01175*
X05904*
Y01175*
X05905*
Y01174*
X05906*
Y01174*
X05908*
Y01173*
X05909*
Y01173*
X0591*
Y01172*
X05911*
Y01172*
X05911*
Y01171*
X05912*
Y01171*
X05913*
Y0117*
X05913*
Y01169*
X05915*
Y01169*
X05915*
Y01168*
X05916*
Y01168*
X05916*
Y01167*
X05917*
Y01167*
X05917*
Y01166*
X05918*
Y01166*
X05918*
Y01165*
X05919*
Y01165*
Y01164*
X05919*
Y01163*
X0592*
Y01163*
X0592*
Y01162*
Y01162*
X05921*
Y01161*
X05922*
Y01161*
Y0116*
X05922*
Y0116*
Y01159*
X05923*
Y01159*
Y01158*
X05923*
Y01158*
Y01157*
X05924*
Y01156*
Y01156*
Y01155*
X05924*
Y01155*
Y01154*
X05925*
Y01154*
Y01153*
Y01153*
Y01152*
X05925*
Y01152*
Y01151*
Y01151*
Y0115*
Y01149*
X05926*
Y01149*
Y01148*
Y01148*
Y01147*
Y01147*
Y01146*
Y01146*
Y01145*
Y01145*
Y01144*
Y01143*
Y01143*
Y01142*
Y01142*
Y01141*
Y01141*
Y0114*
Y0114*
Y01139*
Y01139*
Y01138*
Y01138*
Y01137*
Y01136*
Y01136*
Y01135*
Y01135*
Y01134*
Y01134*
Y01133*
Y01133*
Y01132*
Y01132*
Y01131*
Y01131*
Y0113*
Y01129*
Y01129*
Y01128*
Y01128*
Y01127*
Y01127*
Y01126*
Y01126*
Y01125*
Y01125*
Y01124*
Y01123*
Y01123*
Y01122*
Y01122*
Y01121*
Y01121*
Y0112*
Y0112*
Y01119*
Y01119*
Y01118*
Y01118*
Y01117*
Y01116*
Y01116*
Y01115*
Y01115*
Y01114*
Y01114*
Y01113*
Y01113*
Y01112*
Y01112*
Y01111*
Y01111*
Y0111*
Y01109*
Y01109*
Y01108*
Y01108*
Y01107*
Y01107*
Y01106*
Y01106*
Y01105*
Y01105*
Y01104*
Y01103*
Y01103*
Y01102*
Y01102*
Y01101*
Y01101*
Y011*
Y011*
Y01099*
Y01099*
Y01098*
Y01098*
Y01097*
Y01096*
Y01096*
Y01095*
Y01095*
Y01094*
Y01094*
Y01093*
Y01093*
Y01092*
Y01092*
Y01091*
Y01091*
Y0109*
Y01089*
Y01089*
Y01088*
Y01088*
Y01087*
Y01087*
Y01086*
Y01086*
Y01085*
Y01085*
Y01084*
Y01083*
Y01083*
Y01082*
Y01082*
Y01081*
Y01081*
Y0108*
Y0108*
Y01079*
Y01079*
Y01078*
Y01078*
Y01077*
Y01076*
Y01076*
Y01075*
Y01075*
Y01074*
Y01074*
Y01073*
Y01073*
Y01072*
Y01072*
Y01071*
Y0107*
Y0107*
Y01069*
Y01069*
Y01068*
Y01068*
Y01067*
Y01067*
Y01066*
Y01066*
Y01065*
Y01065*
Y01064*
Y01063*
Y01063*
Y01062*
Y01062*
Y01061*
Y01061*
Y0106*
Y0106*
Y01059*
Y01059*
Y01058*
Y01058*
Y01057*
Y01056*
Y01056*
Y01055*
Y01055*
Y01054*
Y01054*
Y01053*
Y01053*
Y01052*
Y01052*
Y01051*
Y0105*
Y0105*
Y01049*
Y01049*
Y01048*
Y01048*
Y01047*
Y01047*
Y01046*
Y01046*
Y01045*
Y01045*
Y01044*
Y01043*
Y01043*
Y01042*
Y01042*
Y01041*
Y01041*
Y0104*
Y0104*
Y01039*
Y01039*
Y01038*
Y01038*
Y01037*
Y01036*
Y01036*
Y01035*
Y01035*
Y01034*
Y01034*
Y01033*
Y01033*
Y01032*
Y01032*
Y01031*
Y0103*
Y0103*
Y01029*
Y01029*
Y01028*
Y01028*
Y01027*
Y01027*
Y01026*
Y01026*
Y01025*
Y01025*
Y01024*
Y01023*
Y01023*
Y01022*
Y01022*
Y01021*
Y01021*
Y0102*
Y0102*
Y01019*
Y01019*
Y01018*
Y01018*
Y01017*
Y01016*
Y01016*
Y01015*
Y01015*
Y01014*
Y01014*
Y01013*
Y01013*
Y01012*
Y01012*
Y01011*
Y0101*
Y0101*
Y01009*
Y01009*
Y01008*
Y01008*
Y01007*
Y01007*
Y01006*
Y01006*
Y01005*
Y01005*
Y01004*
Y01003*
Y01003*
Y01002*
Y01002*
Y01001*
Y01001*
Y01*
Y01*
Y00999*
Y00999*
Y00998*
Y00998*
Y00997*
Y00996*
Y00996*
Y00995*
Y00995*
Y00994*
Y00994*
Y00993*
Y00993*
Y00992*
Y00992*
Y00991*
Y0099*
Y0099*
Y00989*
Y00989*
Y00988*
Y00988*
Y00987*
Y00987*
Y00986*
Y00986*
Y00985*
Y00985*
Y00984*
Y00983*
Y00983*
Y00982*
Y00982*
Y00981*
Y00981*
Y0098*
Y0098*
Y00979*
Y00979*
Y00978*
Y00978*
Y00977*
Y00976*
Y00976*
Y00975*
Y00975*
Y00974*
Y00974*
Y00973*
Y00973*
Y00972*
Y00972*
Y00971*
Y0097*
Y0097*
Y00969*
Y00969*
Y00968*
Y00968*
Y00967*
Y00967*
Y00966*
Y00966*
Y00965*
Y00965*
Y00964*
Y00963*
Y00963*
Y00962*
Y00962*
Y00961*
Y00961*
Y0096*
Y0096*
Y00959*
Y00959*
Y00958*
Y00958*
Y00957*
Y00956*
Y00956*
Y00955*
Y00955*
Y00954*
Y00954*
Y00953*
Y00953*
Y00952*
Y00952*
Y00951*
Y0095*
Y0095*
Y00949*
Y00949*
Y00948*
Y00948*
Y00947*
Y00947*
Y00946*
Y00946*
Y00945*
Y00945*
Y00944*
Y00943*
Y00943*
Y00942*
Y00942*
Y00941*
Y00941*
Y0094*
Y0094*
Y00939*
Y00939*
Y00938*
Y00938*
Y00937*
Y00936*
Y00936*
Y00935*
Y00935*
Y00934*
Y00934*
Y00933*
Y00933*
Y00932*
Y00932*
Y00931*
Y0093*
Y0093*
Y00929*
Y00929*
Y00928*
Y00928*
Y00927*
Y00927*
Y00926*
Y00926*
Y00925*
Y00925*
Y00924*
Y00923*
Y00923*
Y00922*
Y00922*
Y00921*
Y00921*
Y0092*
Y0092*
Y00919*
Y00919*
Y00918*
Y00918*
Y00917*
Y00916*
Y00916*
Y00915*
Y00915*
Y00914*
Y00914*
Y00913*
Y00913*
Y00912*
Y00912*
Y00911*
Y0091*
Y0091*
Y00909*
Y00909*
Y00908*
Y00908*
Y00907*
Y00907*
Y00906*
Y00906*
Y00905*
Y00905*
Y00904*
Y00903*
Y00903*
Y00902*
Y00902*
Y00901*
Y00901*
Y009*
Y009*
Y00899*
Y00899*
Y00898*
Y00897*
Y00897*
Y00896*
Y00896*
Y00895*
Y00895*
Y00894*
Y00894*
Y00893*
Y00893*
Y00892*
Y00892*
Y00891*
Y0089*
Y0089*
Y00889*
Y00889*
Y00888*
Y00888*
Y00887*
Y00887*
Y00886*
Y00886*
Y00885*
Y00885*
Y00884*
Y00883*
Y00883*
Y00882*
Y00882*
Y00881*
Y00881*
Y0088*
Y0088*
Y00879*
Y00879*
Y00878*
Y00877*
Y00877*
Y00876*
Y00876*
Y00875*
Y00875*
Y00874*
Y00874*
Y00873*
Y00873*
Y00872*
Y00872*
Y00871*
Y0087*
Y0087*
Y00869*
Y00869*
Y00868*
Y00868*
Y00867*
Y00867*
Y00866*
Y00866*
Y00865*
Y00865*
Y00864*
Y00863*
Y00863*
Y00862*
Y00862*
Y00861*
Y00861*
Y0086*
Y0086*
Y00859*
Y00859*
Y00858*
Y00857*
Y00857*
Y00856*
Y00856*
Y00855*
Y00855*
Y00854*
Y00854*
Y00853*
Y00853*
Y00852*
Y00852*
Y00851*
Y0085*
Y0085*
Y00849*
Y00849*
Y00848*
Y00848*
Y00847*
Y00847*
Y00846*
Y00846*
Y00845*
Y00845*
Y00844*
Y00843*
Y00843*
Y00842*
Y00842*
Y00841*
Y00841*
Y0084*
Y0084*
Y00839*
Y00839*
Y00838*
Y00837*
Y00837*
Y00836*
Y00836*
Y00835*
Y00835*
Y00834*
Y00834*
Y00833*
Y00833*
Y00832*
Y00832*
Y00831*
Y0083*
Y0083*
Y00829*
Y00829*
Y00828*
Y00828*
Y00827*
Y00827*
Y00826*
Y00826*
Y00825*
Y00825*
Y00824*
Y00823*
Y00823*
Y00822*
Y00822*
Y00821*
Y00821*
Y0082*
Y0082*
Y00819*
Y00819*
Y00818*
Y00817*
Y00817*
Y00816*
Y00816*
Y00815*
Y00815*
Y00814*
Y00814*
Y00813*
Y00813*
Y00812*
Y00812*
Y00811*
Y0081*
Y0081*
Y00809*
Y00809*
Y00808*
Y00808*
Y00807*
Y00807*
Y00806*
Y00806*
Y00805*
Y00805*
Y00804*
Y00803*
Y00803*
Y00802*
Y00802*
Y00801*
Y00801*
Y008*
Y008*
Y00799*
Y00799*
Y00798*
Y00797*
Y00797*
Y00796*
Y00796*
Y00795*
Y00795*
Y00794*
Y00794*
Y00793*
Y00793*
Y00792*
Y00792*
Y00791*
Y0079*
Y0079*
Y00789*
Y00789*
Y00788*
Y00788*
Y00787*
Y00787*
Y00786*
Y00786*
Y00785*
Y00785*
Y00784*
Y00783*
Y00783*
Y00782*
Y00782*
Y00781*
Y00781*
Y0078*
Y0078*
Y00779*
Y00779*
Y00778*
Y00777*
Y00777*
Y00776*
Y00776*
Y00775*
Y00775*
Y00774*
Y00774*
Y00773*
Y00773*
Y00772*
Y00772*
Y00771*
Y0077*
Y0077*
Y00769*
Y00769*
Y00768*
Y00768*
Y00767*
Y00767*
Y00766*
Y00766*
Y00765*
Y00765*
Y00764*
Y00763*
Y00763*
Y00762*
Y00762*
Y00761*
Y00761*
Y0076*
Y0076*
Y00759*
Y00759*
Y00758*
Y00757*
Y00757*
Y00756*
Y00756*
Y00755*
Y00755*
Y00754*
Y00754*
Y00753*
Y00753*
Y00752*
Y00752*
Y00751*
Y0075*
Y0075*
Y00749*
Y00749*
Y00748*
Y00748*
Y00747*
Y00747*
Y00746*
Y00746*
Y00745*
Y00745*
Y00744*
Y00743*
Y00743*
Y00742*
Y00742*
Y00741*
Y00741*
Y0074*
Y0074*
Y00739*
Y00739*
Y00738*
Y00737*
Y00737*
Y00736*
Y00736*
Y00735*
Y00735*
Y00734*
Y00734*
Y00733*
Y00733*
Y00732*
Y00732*
Y00731*
Y0073*
Y0073*
Y00729*
Y00729*
Y00728*
Y00728*
Y00727*
Y00727*
Y00726*
Y00726*
Y00725*
Y00725*
Y00724*
Y00723*
Y00723*
Y00722*
Y00722*
Y00721*
Y00721*
Y0072*
Y0072*
Y00719*
Y00719*
Y00718*
Y00717*
Y00717*
Y00716*
Y00716*
Y00715*
Y00715*
Y00714*
Y00714*
Y00713*
Y00713*
Y00712*
Y00712*
Y00711*
Y0071*
Y0071*
Y00709*
Y00709*
Y00708*
Y00708*
Y00707*
Y00707*
Y00706*
Y00706*
Y00705*
Y00704*
Y00704*
Y00703*
Y00703*
Y00702*
Y00702*
Y00701*
Y00701*
Y007*
Y007*
Y00699*
Y00699*
Y00698*
Y00697*
Y00697*
Y00696*
Y00696*
Y00695*
Y00695*
Y00694*
Y00694*
Y00693*
Y00693*
Y00692*
Y00692*
Y00691*
Y0069*
Y0069*
Y00689*
Y00689*
Y00688*
Y00688*
Y00687*
Y00687*
Y00686*
Y00686*
Y00685*
Y00684*
Y00684*
Y00683*
Y00683*
Y00682*
Y00682*
Y00681*
Y00681*
Y0068*
Y0068*
Y00679*
Y00679*
Y00678*
Y00677*
Y00677*
Y00676*
Y00676*
Y00675*
Y00675*
Y00674*
Y00674*
Y00673*
Y00673*
Y00672*
Y00672*
Y00671*
Y0067*
Y0067*
Y00669*
Y00669*
Y00668*
Y00668*
Y00667*
Y00667*
Y00666*
Y00666*
Y00665*
Y00664*
Y00664*
Y00663*
Y00663*
Y00662*
Y00662*
Y00661*
Y00661*
Y0066*
Y0066*
Y00659*
Y00659*
Y00658*
Y00657*
Y00657*
Y00656*
Y00656*
Y00655*
Y00655*
Y00654*
Y00654*
Y00653*
Y00653*
Y00652*
Y00652*
Y00651*
Y0065*
Y0065*
Y00649*
Y00649*
Y00648*
Y00648*
Y00647*
Y00647*
Y00646*
Y00646*
Y00645*
Y00644*
Y00644*
Y00643*
Y00643*
Y00642*
Y00642*
Y00641*
Y00641*
Y0064*
Y0064*
Y00639*
Y00639*
Y00638*
Y00637*
Y00637*
Y00636*
Y00636*
Y00635*
Y00635*
Y00634*
Y00634*
Y00633*
Y00633*
Y00632*
Y00632*
Y00631*
Y0063*
Y0063*
Y00629*
Y00629*
Y00628*
Y00628*
Y00627*
Y00627*
Y00626*
Y00626*
Y00625*
Y00624*
Y00624*
Y00623*
Y00623*
Y00622*
Y00622*
Y00621*
Y00621*
Y0062*
Y0062*
Y00619*
Y00619*
Y00618*
Y00617*
Y00617*
Y00616*
Y00616*
Y00615*
Y00615*
Y00614*
Y00614*
Y00613*
Y00613*
Y00612*
Y00612*
Y00611*
Y0061*
Y0061*
Y00609*
Y00609*
Y00608*
Y00608*
Y00607*
Y00607*
Y00606*
Y00606*
Y00605*
Y00604*
Y00604*
Y00603*
Y00603*
Y00602*
Y00602*
Y00601*
Y00601*
Y006*
Y006*
Y00599*
Y00599*
Y00598*
Y00597*
Y00597*
Y00596*
Y00596*
Y00595*
Y00595*
Y00594*
Y00594*
Y00593*
Y00593*
Y00592*
Y00592*
Y00591*
Y0059*
Y0059*
Y00589*
Y00589*
Y00588*
Y00588*
Y00587*
Y00587*
Y00586*
Y00586*
Y00585*
Y00584*
Y00584*
Y00583*
Y00583*
Y00582*
Y00582*
Y00581*
Y00581*
Y0058*
Y0058*
Y00579*
Y00579*
Y00578*
Y00577*
Y00577*
Y00576*
Y00576*
Y00575*
Y00575*
Y00574*
Y00574*
Y00573*
Y00573*
Y00572*
Y00572*
Y00571*
Y0057*
Y0057*
Y00569*
Y00569*
Y00568*
Y00568*
Y00567*
Y00567*
Y00566*
Y00566*
Y00565*
Y00564*
Y00564*
Y00563*
Y00563*
Y00562*
Y00562*
Y00561*
Y00561*
Y0056*
Y0056*
Y00559*
X05906*
Y0056*
Y0056*
Y00561*
Y00561*
Y00562*
Y00562*
Y00563*
Y00563*
Y00564*
Y00564*
Y00565*
Y00566*
Y00566*
Y00567*
Y00567*
Y00568*
Y00568*
Y00569*
Y00569*
Y0057*
Y0057*
Y00571*
Y00572*
Y00572*
Y00573*
Y00573*
Y00574*
Y00574*
Y00575*
Y00575*
Y00576*
Y00576*
Y00577*
Y00577*
Y00578*
Y00579*
Y00579*
Y0058*
Y0058*
Y00581*
Y00581*
Y00582*
Y00582*
Y00583*
Y00583*
Y00584*
Y00584*
Y00585*
Y00586*
Y00586*
Y00587*
Y00587*
Y00588*
Y00588*
Y00589*
Y00589*
Y0059*
Y0059*
Y00591*
Y00592*
Y00592*
Y00593*
Y00593*
Y00594*
Y00594*
Y00595*
Y00595*
Y00596*
Y00596*
Y00597*
Y00597*
Y00598*
Y00599*
Y00599*
Y006*
Y006*
Y00601*
Y00601*
Y00602*
Y00602*
Y00603*
Y00603*
Y00604*
Y00604*
Y00605*
Y00606*
Y00606*
Y00607*
Y00607*
Y00608*
Y00608*
Y00609*
Y00609*
Y0061*
Y0061*
Y00611*
Y00612*
Y00612*
Y00613*
Y00613*
Y00614*
Y00614*
Y00615*
Y00615*
Y00616*
Y00616*
Y00617*
Y00617*
Y00618*
Y00619*
Y00619*
Y0062*
Y0062*
Y00621*
Y00621*
Y00622*
Y00622*
Y00623*
Y00623*
Y00624*
Y00624*
Y00625*
Y00626*
Y00626*
Y00627*
Y00627*
Y00628*
Y00628*
Y00629*
Y00629*
Y0063*
Y0063*
Y00631*
Y00632*
Y00632*
Y00633*
Y00633*
Y00634*
Y00634*
Y00635*
Y00635*
Y00636*
Y00636*
Y00637*
Y00637*
Y00638*
Y00639*
Y00639*
Y0064*
Y0064*
Y00641*
Y00641*
Y00642*
Y00642*
Y00643*
Y00643*
Y00644*
Y00644*
Y00645*
Y00646*
Y00646*
Y00647*
Y00647*
Y00648*
Y00648*
Y00649*
Y00649*
Y0065*
Y0065*
Y00651*
Y00652*
Y00652*
Y00653*
Y00653*
Y00654*
Y00654*
Y00655*
Y00655*
Y00656*
Y00656*
Y00657*
Y00657*
Y00658*
Y00659*
Y00659*
Y0066*
Y0066*
Y00661*
Y00661*
Y00662*
Y00662*
Y00663*
Y00663*
Y00664*
Y00664*
Y00665*
Y00666*
Y00666*
Y00667*
Y00667*
Y00668*
Y00668*
Y00669*
Y00669*
Y0067*
Y0067*
Y00671*
Y00672*
Y00672*
Y00673*
Y00673*
Y00674*
Y00674*
Y00675*
Y00675*
Y00676*
Y00676*
Y00677*
Y00677*
Y00678*
Y00679*
Y00679*
Y0068*
Y0068*
Y00681*
Y00681*
Y00682*
Y00682*
Y00683*
Y00683*
Y00684*
Y00684*
Y00685*
Y00686*
Y00686*
Y00687*
Y00687*
Y00688*
Y00688*
Y00689*
Y00689*
Y0069*
Y0069*
Y00691*
Y00692*
Y00692*
Y00693*
Y00693*
Y00694*
Y00694*
Y00695*
Y00695*
Y00696*
Y00696*
Y00697*
Y00697*
Y00698*
Y00699*
Y00699*
Y007*
Y007*
Y00701*
Y00701*
Y00702*
Y00702*
Y00703*
Y00703*
Y00704*
Y00704*
Y00705*
Y00706*
Y00706*
Y00707*
Y00707*
Y00708*
Y00708*
Y00709*
Y00709*
Y0071*
Y0071*
Y00711*
Y00712*
Y00712*
Y00713*
Y00713*
Y00714*
Y00714*
Y00715*
Y00715*
Y00716*
Y00716*
Y00717*
Y00717*
Y00718*
Y00719*
Y00719*
Y0072*
Y0072*
Y00721*
Y00721*
Y00722*
Y00722*
Y00723*
Y00723*
Y00724*
Y00725*
Y00725*
Y00726*
Y00726*
Y00727*
Y00727*
Y00728*
Y00728*
Y00729*
Y00729*
Y0073*
Y0073*
Y00731*
Y00732*
Y00732*
Y00733*
Y00733*
Y00734*
Y00734*
Y00735*
Y00735*
Y00736*
Y00736*
Y00737*
Y00737*
Y00738*
Y00739*
Y00739*
Y0074*
Y0074*
Y00741*
Y00741*
Y00742*
Y00742*
Y00743*
Y00743*
Y00744*
Y00745*
Y00745*
Y00746*
Y00746*
Y00747*
Y00747*
Y00748*
Y00748*
Y00749*
Y00749*
Y0075*
Y0075*
Y00751*
Y00752*
Y00752*
Y00753*
Y00753*
Y00754*
Y00754*
Y00755*
Y00755*
Y00756*
Y00756*
Y00757*
Y00757*
Y00758*
Y00759*
Y00759*
Y0076*
Y0076*
Y00761*
Y00761*
Y00762*
Y00762*
Y00763*
Y00763*
Y00764*
Y00765*
Y00765*
Y00766*
Y00766*
Y00767*
Y00767*
Y00768*
Y00768*
Y00769*
Y00769*
Y0077*
Y0077*
Y00771*
Y00772*
Y00772*
Y00773*
Y00773*
Y00774*
Y00774*
Y00775*
Y00775*
Y00776*
Y00776*
Y00777*
Y00777*
Y00778*
Y00779*
Y00779*
Y0078*
Y0078*
Y00781*
Y00781*
Y00782*
Y00782*
Y00783*
Y00783*
Y00784*
Y00785*
Y00785*
Y00786*
Y00786*
Y00787*
Y00787*
Y00788*
Y00788*
Y00789*
Y00789*
Y0079*
Y0079*
Y00791*
Y00792*
Y00792*
Y00793*
Y00793*
Y00794*
Y00794*
Y00795*
Y00795*
Y00796*
Y00796*
Y00797*
Y00797*
Y00798*
Y00799*
Y00799*
Y008*
Y008*
Y00801*
Y00801*
Y00802*
Y00802*
Y00803*
Y00803*
Y00804*
Y00805*
Y00805*
Y00806*
Y00806*
Y00807*
Y00807*
Y00808*
Y00808*
Y00809*
Y00809*
Y0081*
Y0081*
Y00811*
Y00812*
Y00812*
Y00813*
Y00813*
Y00814*
Y00814*
Y00815*
Y00815*
Y00816*
Y00816*
Y00817*
Y00817*
Y00818*
Y00819*
Y00819*
Y0082*
Y0082*
Y00821*
Y00821*
Y00822*
Y00822*
Y00823*
Y00823*
Y00824*
Y00825*
Y00825*
Y00826*
Y00826*
Y00827*
Y00827*
Y00828*
Y00828*
Y00829*
Y00829*
Y0083*
Y0083*
Y00831*
Y00832*
Y00832*
Y00833*
Y00833*
Y00834*
Y00834*
Y00835*
Y00835*
Y00836*
Y00836*
Y00837*
Y00837*
Y00838*
Y00839*
Y00839*
Y0084*
Y0084*
Y00841*
Y00841*
Y00842*
Y00842*
Y00843*
Y00843*
Y00844*
Y00845*
Y00845*
Y00846*
Y00846*
Y00847*
Y00847*
Y00848*
Y00848*
Y00849*
Y00849*
Y0085*
Y0085*
Y00851*
Y00852*
Y00852*
Y00853*
Y00853*
Y00854*
Y00854*
Y00855*
Y00855*
Y00856*
Y00856*
Y00857*
Y00857*
Y00858*
Y00859*
Y00859*
Y0086*
Y0086*
Y00861*
Y00861*
Y00862*
Y00862*
Y00863*
Y00863*
Y00864*
Y00865*
Y00865*
Y00866*
Y00866*
Y00867*
Y00867*
Y00868*
Y00868*
Y00869*
Y00869*
Y0087*
Y0087*
Y00871*
Y00872*
Y00872*
Y00873*
Y00873*
Y00874*
Y00874*
Y00875*
Y00875*
Y00876*
Y00876*
Y00877*
Y00877*
Y00878*
Y00879*
Y00879*
Y0088*
Y0088*
Y00881*
Y00881*
Y00882*
Y00882*
Y00883*
Y00883*
Y00884*
Y00885*
Y00885*
Y00886*
Y00886*
Y00887*
Y00887*
Y00888*
Y00888*
Y00889*
Y00889*
Y0089*
Y0089*
Y00891*
Y00892*
Y00892*
Y00893*
Y00893*
Y00894*
Y00894*
Y00895*
Y00895*
Y00896*
Y00896*
Y00897*
Y00897*
Y00898*
Y00899*
Y00899*
Y009*
Y009*
Y00901*
Y00901*
Y00902*
Y00902*
Y00903*
Y00903*
Y00904*
Y00905*
Y00905*
Y00906*
Y00906*
Y00907*
Y00907*
Y00908*
Y00908*
Y00909*
Y00909*
Y0091*
Y0091*
Y00911*
Y00912*
Y00912*
Y00913*
Y00913*
Y00914*
Y00914*
Y00915*
Y00915*
Y00916*
Y00916*
Y00917*
Y00918*
Y00918*
Y00919*
Y00919*
Y0092*
Y0092*
Y00921*
Y00921*
Y00922*
Y00922*
Y00923*
Y00923*
Y00924*
Y00925*
Y00925*
Y00926*
Y00926*
Y00927*
Y00927*
Y00928*
Y00928*
Y00929*
Y00929*
Y0093*
Y0093*
Y00931*
Y00932*
Y00932*
Y00933*
Y00933*
Y00934*
Y00934*
Y00935*
Y00935*
Y00936*
Y00936*
Y00937*
Y00938*
Y00938*
Y00939*
Y00939*
Y0094*
Y0094*
Y00941*
Y00941*
Y00942*
Y00942*
Y00943*
Y00943*
Y00944*
Y00945*
Y00945*
Y00946*
Y00946*
Y00947*
Y00947*
Y00948*
Y00948*
Y00949*
Y00949*
Y0095*
Y0095*
Y00951*
Y00952*
Y00952*
Y00953*
Y00953*
Y00954*
Y00954*
Y00955*
Y00955*
Y00956*
Y00956*
Y00957*
Y00958*
Y00958*
Y00959*
Y00959*
Y0096*
Y0096*
Y00961*
Y00961*
Y00962*
Y00962*
Y00963*
Y00963*
Y00964*
Y00965*
Y00965*
Y00966*
Y00966*
Y00967*
Y00967*
Y00968*
Y00968*
Y00969*
Y00969*
Y0097*
Y0097*
Y00971*
Y00972*
Y00972*
Y00973*
Y00973*
Y00974*
Y00974*
Y00975*
Y00975*
Y00976*
Y00976*
Y00977*
Y00978*
Y00978*
Y00979*
Y00979*
Y0098*
Y0098*
Y00981*
Y00981*
Y00982*
Y00982*
Y00983*
Y00983*
Y00984*
Y00985*
Y00985*
Y00986*
Y00986*
Y00987*
Y00987*
Y00988*
Y00988*
Y00989*
Y00989*
Y0099*
Y0099*
Y00991*
Y00992*
Y00992*
Y00993*
Y00993*
Y00994*
Y00994*
Y00995*
Y00995*
Y00996*
Y00996*
Y00997*
Y00998*
Y00998*
Y00999*
Y00999*
Y01*
Y01*
Y01001*
Y01001*
Y01002*
Y01002*
Y01003*
Y01003*
Y01004*
Y01005*
Y01005*
Y01006*
Y01006*
Y01007*
Y01007*
Y01008*
Y01008*
Y01009*
Y01009*
Y0101*
Y0101*
Y01011*
Y01012*
Y01012*
Y01013*
Y01013*
Y01014*
Y01014*
Y01015*
Y01015*
Y01016*
Y01016*
Y01017*
Y01018*
Y01018*
Y01019*
Y01019*
Y0102*
Y0102*
Y01021*
Y01021*
Y01022*
Y01022*
Y01023*
Y01023*
Y01024*
Y01025*
Y01025*
Y01026*
Y01026*
Y01027*
Y01027*
Y01028*
Y01028*
Y01029*
Y01029*
Y0103*
Y0103*
Y01031*
Y01032*
Y01032*
Y01033*
Y01033*
Y01034*
Y01034*
Y01035*
Y01035*
Y01036*
Y01036*
Y01037*
Y01038*
Y01038*
Y01039*
Y01039*
Y0104*
Y0104*
Y01041*
Y01041*
Y01042*
Y01042*
Y01043*
Y01043*
Y01044*
Y01045*
Y01045*
Y01046*
Y01046*
Y01047*
Y01047*
Y01048*
Y01048*
Y01049*
Y01049*
Y0105*
Y0105*
Y01051*
Y01052*
Y01052*
Y01053*
Y01053*
Y01054*
Y01054*
Y01055*
Y01055*
Y01056*
Y01056*
Y01057*
Y01058*
Y01058*
Y01059*
Y01059*
Y0106*
Y0106*
Y01061*
Y01061*
Y01062*
Y01062*
Y01063*
Y01063*
Y01064*
Y01065*
Y01065*
Y01066*
Y01066*
Y01067*
Y01067*
Y01068*
Y01068*
Y01069*
Y01069*
Y0107*
Y0107*
Y01071*
Y01072*
Y01072*
Y01073*
Y01073*
Y01074*
Y01074*
Y01075*
Y01075*
Y01076*
Y01076*
Y01077*
Y01078*
Y01078*
Y01079*
Y01079*
Y0108*
Y0108*
Y01081*
Y01081*
Y01082*
Y01082*
Y01083*
Y01083*
Y01084*
Y01085*
Y01085*
Y01086*
Y01086*
Y01087*
Y01087*
Y01088*
Y01088*
Y01089*
Y01089*
Y0109*
Y01091*
Y01091*
Y01092*
Y01092*
Y01093*
Y01093*
Y01094*
Y01094*
Y01095*
Y01095*
Y01096*
Y01096*
Y01097*
Y01098*
Y01098*
Y01099*
Y01099*
Y011*
Y011*
Y01101*
Y01101*
Y01102*
Y01102*
Y01103*
Y01103*
Y01104*
Y01105*
Y01105*
Y01106*
Y01106*
Y01107*
Y01107*
Y01108*
Y01108*
Y01109*
Y01109*
Y0111*
Y01111*
Y01111*
Y01112*
Y01112*
Y01113*
Y01113*
Y01114*
Y01114*
Y01115*
Y01115*
Y01116*
Y01116*
Y01117*
Y01118*
Y01118*
Y01119*
Y01119*
Y0112*
Y0112*
Y01121*
Y01121*
Y01122*
Y01122*
Y01123*
Y01123*
Y01124*
Y01125*
Y01125*
Y01126*
Y01126*
Y01127*
Y01127*
Y01128*
Y01128*
Y01129*
Y01129*
Y0113*
Y01131*
Y01131*
Y01132*
Y01132*
Y01133*
Y01133*
Y01134*
Y01134*
Y01135*
Y01135*
Y01136*
Y01136*
Y01137*
Y01138*
Y01138*
Y01139*
Y01139*
Y0114*
Y0114*
Y01141*
Y01141*
Y01142*
Y01142*
Y01143*
Y01143*
Y01144*
X05905*
Y01145*
Y01145*
Y01146*
Y01146*
Y01147*
X05905*
Y01147*
Y01148*
X05904*
Y01148*
Y01149*
X05904*
Y01149*
Y0115*
X05903*
Y01151*
X05903*
Y01151*
Y01152*
X05902*
Y01152*
X05902*
Y01153*
X05901*
Y01153*
X059*
Y01154*
X05899*
Y01154*
X05898*
Y01155*
X05897*
Y01155*
X05896*
Y01156*
X05894*
Y01156*
X05825*
Y01157*
Y01158*
Y01158*
Y01159*
Y01159*
Y0116*
Y0116*
Y01161*
Y01161*
Y01162*
Y01162*
Y01163*
Y01163*
Y01164*
Y01165*
Y01165*
Y01166*
Y01166*
Y01167*
Y01167*
Y01168*
Y01168*
Y01169*
Y01169*
Y0117*
Y01171*
Y01171*
Y01172*
Y01172*
Y01173*
Y01173*
Y01174*
Y01174*
Y01175*
Y01175*
Y01176*
Y01176*
Y01177*
X05894*
Y01176*
G37*
%LNtimingcard_pcb-2*%
%LPC*%
G36*
X069Y03647D02*
X06885Y03645D01*
X06871Y03639*
X06859Y0363*
X0685Y03618*
X06844Y03604*
X06842Y03589*
X06844Y03574*
X0685Y0356*
X06859Y03548*
X06871Y03539*
X06885Y03533*
X069Y03531*
X06915Y03533*
X06929Y03539*
X06941Y03548*
X0695Y0356*
X06955Y03574*
X06957Y03589*
X06955Y03604*
X0695Y03618*
X06941Y0363*
X06929Y03639*
X06915Y03645*
X069Y03647*
G37*
G36*
X06734D02*
X06719Y03645D01*
X06705Y03639*
X06694Y0363*
X06684Y03618*
X06679Y03604*
X06677Y03589*
X06679Y03574*
X06684Y0356*
X06694Y03548*
X06705Y03539*
X06719Y03533*
X06734Y03531*
X06749Y03533*
X06763Y03539*
X06775Y03548*
X06784Y0356*
X0679Y03574*
X06792Y03589*
X0679Y03604*
X06784Y03618*
X06775Y0363*
X06763Y03639*
X06749Y03645*
X06734Y03647*
G37*
G36*
X06569D02*
X06554Y03645D01*
X0654Y03639*
X06528Y0363*
X06519Y03618*
X06513Y03604*
X06511Y03589*
X06513Y03574*
X06519Y0356*
X06528Y03548*
X0654Y03539*
X06554Y03533*
X06569Y03531*
X06584Y03533*
X06598Y03539*
X0661Y03548*
X06619Y0356*
X06625Y03574*
X06627Y03589*
X06625Y03604*
X06619Y03618*
X0661Y0363*
X06598Y03639*
X06584Y03645*
X06569Y03647*
G37*
G36*
X03622Y03502D02*
X03616Y03501D01*
X03612Y03498*
X03566*
X03562Y03497*
X03558Y03494*
X0351Y03446*
X03507Y03442*
X03506Y03438*
X03483*
X03482Y03439*
X03481Y03444*
X03484Y03449*
X03486Y03456*
X03484Y03462*
X03481Y03467*
X03476Y03471*
X03469Y03472*
X03463Y03471*
X03458Y03467*
X03454Y03462*
X03453Y03456*
X03454Y03449*
X03458Y03444*
X03459Y03443*
X03458Y03438*
X03446*
X03446Y03439*
X03444Y03443*
X03431Y03456*
X03433Y0346*
X03437Y0346*
X03443Y03461*
X03448Y03464*
X03452Y0347*
X03453Y03476*
X03452Y03482*
X03448Y03487*
X03443Y03491*
X03437Y03492*
X0343Y03491*
X03425Y03487*
X03421Y03482*
X0342Y03476*
X03421Y03473*
X03416Y0347*
X03411Y03475*
X03407Y03478*
X03403Y03479*
X03377*
X03373Y03478*
X03369Y03475*
X03357Y03464*
X03352Y03463*
X03349Y03461*
X03239*
X03234Y0346*
X0323Y03457*
X03126Y03353*
X03123Y03349*
X03122Y03344*
Y03307*
X03083*
X03075Y03305*
X03069Y03301*
X03065Y03294*
X03063Y03287*
X03065Y03279*
X03069Y03272*
X03075Y03268*
X03083Y03267*
X03138*
X03146Y03268*
X03153Y03272*
X03157Y03279*
X03158Y03287*
X03157Y03294*
X03153Y03301*
X03147Y03305*
Y03339*
X03244Y03436*
X03305*
Y03362*
X03302Y0336*
X03296Y03359*
X03291Y03355*
X03287Y0335*
X03286Y03344*
X03287Y03337*
X03291Y03332*
X03296Y03328*
X03302Y03327*
X03309Y03328*
X03312Y03331*
X03317Y03329*
Y0331*
X03315Y03307*
X03314Y03301*
X03315Y03294*
X03319Y03289*
X03321Y03287*
X03321Y03287*
X0332Y03282*
X03265*
X03265Y03287*
X03266Y03288*
X03269Y03288*
X03275Y03292*
X03278Y03297*
X0328Y03303*
X03278Y0331*
X03275Y03315*
X03269Y03318*
X03263Y0332*
X03257Y03318*
X03252Y03315*
X03248Y0331*
X03247Y03303*
X03248Y03297*
X03252Y03292*
X03257Y03288*
X0326Y03288*
X03262Y03287*
X03261Y03282*
X03205*
X03201Y03281*
X03197Y03279*
X03167Y03249*
X03154*
X03153Y03251*
X03146Y03255*
X03138Y03257*
X03083*
X03075Y03255*
X03069Y03251*
X03065Y03244*
X03063Y03237*
X03065Y03229*
X03069Y03222*
X03075Y03218*
X03083Y03217*
X03138*
X03146Y03218*
X03153Y03222*
X03154Y03224*
X03172*
X03176Y03225*
X0318Y03228*
X0321Y03258*
X03328*
X03333Y03259*
X03337Y03262*
X03354Y03279*
X03359Y03276*
X03358Y03273*
X03359Y03266*
X03363Y03261*
X03368Y03257*
X03374Y03256*
X03381Y03257*
X03386Y03261*
X03389Y03266*
X03391Y03273*
X03389Y03279*
X03386Y03284*
X03381Y03288*
X03374Y03289*
X03371Y03288*
X03368Y03293*
X03393Y03318*
X03423Y03288*
X03427Y03285*
X03431Y03284*
X03481*
X03485Y03281*
X03491Y0328*
X03498Y03281*
X03503Y03285*
X03506Y0329*
X03508Y03297*
X03506Y03303*
X03503Y03308*
X03498Y03312*
X03491Y03313*
X03485Y03312*
X03481Y03309*
X03436*
X03405Y0334*
Y03351*
X03419*
X03423*
X03477*
X03478*
X03482*
X03483*
X03536*
X03537*
X03541Y03348*
Y03334*
X03536Y03333*
X03531Y0333*
X03527Y03324*
X03526Y03318*
X03527Y03312*
X03531Y03307*
X03536Y03303*
X03542Y03302*
X03549Y03303*
X03554Y03307*
X03557Y03312*
X03559Y03318*
X03557Y03324*
X03556Y03327*
X03559Y03332*
X03597*
Y03438*
X03543*
X03541Y03443*
X03571Y03473*
X03612*
X03616Y0347*
X03622Y03469*
X03629Y0347*
X03634Y03474*
X03637Y03479*
X03639Y03486*
X03637Y03492*
X03634Y03497*
X03629Y03501*
X03622Y03502*
G37*
G36*
X0307Y0341D02*
X03064Y03408D01*
X03059Y03405*
X03046*
X03042Y03404*
X03038Y03401*
X02835Y03199*
X028*
X02798Y03201*
X02792Y03205*
X02784Y03207*
X02729*
X02721Y03205*
X02715Y03201*
X0271Y03194*
X02709Y03187*
X0271Y03179*
X02715Y03172*
X02721Y03168*
X02729Y03167*
X02784*
X02792Y03168*
X02798Y03172*
X028Y03174*
X0284*
X02845Y03175*
X02849Y03178*
X03051Y03381*
X0306*
X03064Y03378*
X0307Y03377*
X03077Y03378*
X03082Y03382*
X03085Y03387*
X03087Y03393*
X03085Y03399*
X03082Y03405*
X03077Y03408*
X0307Y0341*
G37*
G36*
X04438Y0337D02*
X04432Y03369D01*
X04427Y03366*
X04423Y0336*
X04422Y03354*
X04423Y03348*
X04427Y03342*
X04432Y03339*
X04438Y03338*
X04445Y03339*
X0445Y03342*
X04454Y03348*
X04455Y03354*
X04454Y0336*
X0445Y03366*
X04445Y03369*
X04438Y0337*
G37*
G36*
X02784Y03307D02*
X02729D01*
X02721Y03305*
X02715Y03301*
X0271Y03294*
X02709Y03287*
X0271Y03279*
X02715Y03272*
X02721Y03268*
X02729Y03267*
X02784*
X02792Y03268*
X02798Y03272*
X02803Y03279*
X02804Y03287*
X02803Y03294*
X02798Y03301*
X02792Y03305*
X02784Y03307*
G37*
G36*
X03482Y03249D02*
X03478D01*
X03477*
X03424*
X03423*
X03419*
X03418*
X03365*
X03364*
X0336*
X03359*
X03305*
Y0318*
X03282Y03156*
X03281Y03156*
X03275Y03158*
X03269Y03156*
X03264Y03153*
X0326Y03147*
X03259Y03141*
X0326Y03135*
X03264Y0313*
X03269Y03126*
X03275Y03125*
X03281Y03126*
X03287Y0313*
X03287Y03131*
X0329Y03131*
X03294Y03134*
X03322Y03162*
X03359*
X0336*
X03364*
X03365*
X03418*
X03419*
X03423*
X03424*
X03477*
X03478*
X03482*
X03483*
X03537*
Y03249*
X03483*
X03482*
G37*
G36*
X03744Y03277D02*
X03738Y03276D01*
X03733Y03272*
X03729Y03267*
X03728Y03261*
X03729Y03254*
X03733Y03249*
X03738Y03245*
X03744Y03244*
X03751Y03245*
X03756Y03249*
X03759Y03254*
X03761Y03261*
X03759Y03267*
X03756Y03272*
X03751Y03276*
X03744Y03277*
G37*
G36*
X0323Y03251D02*
X03224Y0325D01*
X03219Y03246*
X03215Y03241*
X03214Y03235*
X03215Y03228*
X03219Y03223*
X03224Y03219*
X0323Y03218*
X03237Y03219*
X03242Y03223*
X03245Y03228*
X03247Y03235*
X03245Y03241*
X03242Y03246*
X03237Y0325*
X0323Y03251*
G37*
G36*
X03806D02*
X038Y0325D01*
X03795Y03246*
X03791Y03241*
X0379Y03235*
X03791Y03228*
X03795Y03223*
X03797Y03222*
X03796Y03216*
X03793Y03216*
X03788Y03212*
X03784Y03207*
X03783Y03201*
X03784Y03194*
X03788Y03189*
X03793Y03185*
X03799Y03184*
X03806Y03185*
X03811Y03189*
X03814Y03194*
X03816Y03201*
X03814Y03207*
X03811Y03212*
X03809Y03214*
X0381Y03219*
X03813Y03219*
X03818Y03223*
X03821Y03228*
X03823Y03235*
X03821Y03241*
X03818Y03246*
X03813Y0325*
X03806Y03251*
G37*
G36*
X03138Y03207D02*
X03083D01*
X03075Y03205*
X03069Y03201*
X03065Y03194*
X03063Y03187*
X03065Y03179*
X03069Y03172*
X03075Y03168*
X03083Y03167*
X03138*
X03146Y03168*
X03153Y03172*
X03154Y03174*
X03178*
X03182Y03171*
X03188Y0317*
X03195Y03171*
X032Y03175*
X03204Y0318*
X03205Y03187*
X03204Y03193*
X032Y03198*
X03195Y03202*
X03188Y03203*
X03182Y03202*
X03178Y03199*
X03154*
X03153Y03201*
X03146Y03205*
X03138Y03207*
G37*
G36*
X03829Y03192D02*
X03823Y03191D01*
X03818Y03187*
X03814Y03182*
X03813Y03176*
X03814Y03169*
X03818Y03164*
X03823Y0316*
X03829Y03159*
X03836Y0316*
X03836Y03161*
X03839Y03157*
X03839Y03157*
X03838Y03151*
X03839Y03144*
X03843Y03139*
X03848Y03135*
X03854Y03134*
X03861Y03135*
X03866Y03139*
X03869Y03144*
X03871Y03151*
X03869Y03157*
X03866Y03162*
X03861Y03166*
X03854Y03167*
X03848Y03166*
X03848Y03165*
X03844Y03169*
X03844Y03169*
X03846Y03176*
X03844Y03182*
X03841Y03187*
X03836Y03191*
X03829Y03192*
G37*
G36*
X03138Y03157D02*
X03083D01*
X03075Y03155*
X03069Y03151*
X03065Y03144*
X03063Y03137*
X03065Y03129*
X03069Y03122*
X03075Y03118*
X03083Y03117*
X03138*
X03146Y03118*
X03153Y03122*
X03153Y03123*
X03172*
X03176Y0312*
X03183Y03119*
X03189Y0312*
X03194Y03124*
X03198Y03129*
X03199Y03135*
X03198Y03142*
X03194Y03147*
X03189Y0315*
X03183Y03152*
X03176Y0315*
X03172Y03148*
X03155*
X03153Y03151*
X03146Y03155*
X03138Y03157*
G37*
G36*
X0424Y03282D02*
X04178D01*
Y03209*
X04196*
Y03144*
X04193Y03141*
X04192Y03135*
X04193Y03128*
X04197Y03123*
X04196Y03118*
X04196Y03117*
X04178*
X04177Y03122*
X04174Y03126*
X04168Y03132*
X04169Y03135*
X04167Y03141*
X04164Y03146*
X04159Y0315*
X04152Y03151*
X04146Y0315*
X04141Y03146*
X04137Y03141*
X04136Y03135*
X04137Y03128*
X04141Y03123*
X04141Y03123*
X04141Y03122*
X04142Y03122*
X04139Y03117*
X04127*
X04127Y03118*
X04126Y03123*
X04129Y03128*
X04131Y03135*
X04129Y03141*
X04126Y03146*
X04121Y0315*
X04114Y03151*
X04108Y0315*
X04103Y03146*
X04099Y03141*
X04098Y03135*
X04098Y03133*
X04097Y03131*
X04096Y03126*
Y03117*
X0408*
Y03059*
X043*
X04304*
X04309*
X0436*
X04364*
X04369*
X0442*
X04424*
X04425*
X04484*
Y03117*
X04486Y03121*
X04487Y03121*
X04489Y03123*
X04492Y03128*
X04494Y03135*
X04492Y03141*
X04489Y03146*
X04484Y0315*
X04477Y03151*
X04471Y0315*
X04466Y03146*
X04462Y03141*
X04461Y03135*
X04461Y03133*
X04453Y03124*
X04447Y03126*
X04446Y03128*
X04446Y03128*
X04448Y03135*
X04446Y03141*
X04443Y03146*
X04438Y0315*
X04431Y03151*
X04425Y0315*
X0442Y03146*
X04416Y03141*
X04415Y03135*
X04416Y03128*
X04418Y03126*
Y0312*
X04414Y03117*
X04369*
X04365*
X0436*
X04348*
Y03127*
X04348Y03128*
X0435Y03135*
X04348Y03141*
X04345Y03146*
X0434Y0315*
X04333Y03151*
X04327Y0315*
X04322Y03146*
X04318Y03141*
X04317Y03135*
X04318Y03128*
X04321Y03124*
Y0312*
X04318Y03117*
X04305*
X043*
X04286*
Y03126*
X04287Y03128*
X04289Y03135*
X04287Y03141*
X04284Y03146*
X04279Y0315*
X04272Y03151*
X04266Y0315*
X04261Y03146*
X04257Y03141*
X04256Y03135*
X04257Y03128*
X04259Y03126*
Y03117*
X04233*
Y0312*
X04232Y03125*
X04229Y03129*
X04224Y03133*
X04225Y03135*
X04223Y03141*
X04222Y03143*
Y03209*
X0424*
Y03282*
G37*
G36*
X02784Y03157D02*
X02729D01*
X02721Y03155*
X02715Y03151*
X0271Y03144*
X02709Y03137*
X0271Y03129*
X02715Y03122*
X02721Y03118*
X02729Y03117*
X02784*
X02792Y03118*
X02798Y03122*
X02803Y03129*
X02804Y03137*
X02803Y03144*
X02798Y03151*
X02792Y03155*
X02784Y03157*
G37*
G36*
X03939Y03137D02*
X03933Y03136D01*
X03928Y03132*
X03924Y03127*
X03923Y03121*
X03924Y03114*
X03928Y03109*
X03933Y03105*
X03939Y03104*
X03946Y03105*
X03951Y03109*
X03954Y03114*
X03956Y03121*
X03954Y03127*
X03951Y03132*
X03946Y03136*
X03939Y03137*
G37*
G36*
X03138Y03107D02*
X03083D01*
X03075Y03105*
X03069Y03101*
X03065Y03094*
X03063Y03087*
X03065Y03079*
X03069Y03072*
X03075Y03068*
X03083Y03067*
X03138*
X03146Y03068*
X03153Y03072*
X03157Y03079*
X03158Y03087*
X03157Y03094*
X03153Y03101*
X03146Y03105*
X03138Y03107*
G37*
G36*
X02784D02*
X02729D01*
X02721Y03105*
X02715Y03101*
X0271Y03094*
X02709Y03087*
X0271Y03079*
X02715Y03072*
X02721Y03068*
X02729Y03067*
X02784*
X02792Y03068*
X02798Y03072*
X02803Y03079*
X02804Y03087*
X02803Y03094*
X02798Y03101*
X02792Y03105*
X02784Y03107*
G37*
G36*
X04068Y03151D02*
X04062Y0315D01*
X04057Y03146*
X04053Y03141*
X04053Y03138*
X04043Y03128*
X0404Y03124*
X04039Y0312*
X04013*
Y03064*
X04066*
Y03114*
X04071Y03119*
X04075Y03119*
X0408Y03123*
X04083Y03128*
X04085Y03135*
X04083Y03141*
X0408Y03146*
X04075Y0315*
X04068Y03151*
G37*
G36*
X03801Y03111D02*
X03742D01*
Y03054*
X03801*
Y03064*
X0387*
X03871Y03063*
X03877Y03062*
X03884Y03063*
X03889Y03067*
X03893Y03072*
X03894Y03078*
X03893Y03084*
X03889Y0309*
X03884Y03093*
X03877Y03095*
X03871Y03093*
X0387Y03093*
X03801*
Y03111*
G37*
G36*
X0373Y03148D02*
X03657D01*
Y03086*
X0369*
Y03085*
X03691Y0308*
X03694Y03076*
X03702Y03069*
X03702Y03065*
X03706Y0306*
X03711Y03056*
X03717Y03055*
X03724Y03056*
X03729Y0306*
X03732Y03065*
X03734Y03072*
X03732Y03078*
X0373Y03082*
X0373Y03086*
Y03148*
G37*
G36*
X03138Y03057D02*
X03083D01*
X03075Y03055*
X03069Y03051*
X03065Y03044*
X03063Y03037*
X03065Y03029*
X03069Y03022*
X03075Y03018*
X03083Y03017*
X03138*
X03146Y03018*
X03153Y03022*
X03157Y03029*
X03158Y03037*
X03157Y03044*
X03153Y03051*
X03146Y03055*
X03138Y03057*
G37*
G36*
X02784D02*
X02729D01*
X02721Y03055*
X02715Y03051*
X0271Y03044*
X02709Y03037*
X0271Y03029*
X02715Y03022*
X02721Y03018*
X02729Y03017*
X02784*
X02792Y03018*
X02798Y03022*
X02803Y03029*
X02804Y03037*
X02803Y03044*
X02798Y03051*
X02792Y03055*
X02784Y03057*
G37*
G36*
X03138Y03007D02*
X03083D01*
X03075Y03005*
X03069Y03001*
X03065Y02994*
X03063Y02987*
X03065Y02979*
X03069Y02972*
X03075Y02968*
X03083Y02967*
X03138*
X03146Y02968*
X03153Y02972*
X03157Y02979*
X03158Y02987*
X03157Y02994*
X03153Y03001*
X03146Y03005*
X03138Y03007*
G37*
G36*
X02784D02*
X02729D01*
X02721Y03005*
X02715Y03001*
X0271Y02994*
X02709Y02987*
X0271Y02979*
X02715Y02972*
X02721Y02968*
X02729Y02967*
X02784*
X02792Y02968*
X02798Y02972*
X02803Y02979*
X02804Y02987*
X02803Y02994*
X02798Y03001*
X02792Y03005*
X02784Y03007*
G37*
G36*
X03138Y02957D02*
X03083D01*
X03075Y02955*
X03069Y02951*
X03065Y02944*
X03063Y02937*
X03065Y02929*
X03069Y02922*
X03075Y02918*
X03083Y02917*
X03138*
X03146Y02918*
X03153Y02922*
X03157Y02929*
X03158Y02937*
X03157Y02944*
X03153Y02951*
X03146Y02955*
X03138Y02957*
G37*
G36*
X02784D02*
X02729D01*
X02721Y02955*
X02715Y02951*
X0271Y02944*
X02709Y02937*
X0271Y02929*
X02715Y02922*
X02721Y02918*
X02729Y02917*
X02784*
X02792Y02918*
X02798Y02922*
X02803Y02929*
X02804Y02937*
X02803Y02944*
X02798Y02951*
X02792Y02955*
X02784Y02957*
G37*
G36*
X06391Y01045D02*
X0639D01*
Y01045*
X06389*
Y01045*
X06326*
Y01045*
X06323*
Y01044*
X06322*
Y01043*
X06321*
Y01043*
X0632*
Y01042*
X06319*
Y01042*
X06319*
Y01041*
X06318*
Y01041*
X06318*
Y0104*
X06317*
Y0104*
X06317*
Y01039*
X06316*
Y01039*
X06316*
Y01038*
X06315*
Y01038*
X06315*
Y01037*
X06314*
Y01036*
X06314*
Y01036*
X06313*
Y01035*
X06312*
Y01035*
X06312*
Y01034*
X06311*
Y01034*
X06311*
Y01033*
X0631*
Y01033*
X0631*
Y01032*
X06309*
Y01032*
X06309*
Y01031*
X06308*
Y0103*
X06308*
Y0103*
X06307*
Y01029*
X06306*
Y01029*
X06306*
Y01028*
X06305*
Y01028*
X06305*
Y01027*
Y01027*
Y01026*
X06304*
Y01026*
Y01025*
Y01025*
Y01024*
Y01023*
X06304*
Y01023*
Y01022*
Y01022*
Y01021*
Y01021*
Y0102*
Y0102*
Y01019*
Y01019*
Y01018*
Y01018*
Y01017*
Y01016*
Y01016*
Y01015*
Y01015*
Y01014*
Y01014*
Y01013*
Y01013*
Y01012*
Y01012*
Y01011*
Y0101*
Y0101*
Y01009*
Y01009*
Y01008*
Y01008*
Y01007*
Y01007*
Y01006*
Y01006*
Y01005*
Y01005*
Y01004*
Y01003*
Y01003*
Y01002*
Y01002*
Y01001*
Y01001*
Y01*
Y01*
Y00999*
Y00999*
Y00998*
Y00998*
Y00997*
Y00996*
Y00996*
Y00995*
Y00995*
Y00994*
Y00994*
Y00993*
Y00993*
Y00992*
Y00992*
Y00991*
Y0099*
Y0099*
Y00989*
Y00989*
Y00988*
Y00988*
Y00987*
Y00987*
Y00986*
Y00986*
Y00985*
Y00985*
Y00984*
Y00983*
Y00983*
Y00982*
Y00982*
Y00981*
Y00981*
Y0098*
Y0098*
Y00979*
Y00979*
Y00978*
Y00978*
Y00977*
Y00976*
Y00976*
Y00975*
Y00975*
Y00974*
Y00974*
Y00973*
Y00973*
Y00972*
Y00972*
Y00971*
Y0097*
Y0097*
Y00969*
Y00969*
Y00968*
Y00968*
Y00967*
Y00967*
Y00966*
Y00966*
Y00965*
Y00965*
Y00964*
Y00963*
Y00963*
Y00962*
Y00962*
Y00961*
Y00961*
Y0096*
Y0096*
Y00959*
Y00959*
Y00958*
Y00958*
Y00957*
Y00956*
Y00956*
Y00955*
Y00955*
Y00954*
Y00954*
Y00953*
Y00953*
Y00952*
Y00952*
Y00951*
Y0095*
Y0095*
Y00949*
Y00949*
Y00948*
X06304*
Y00948*
Y00947*
Y00947*
Y00946*
Y00946*
X06305*
Y00945*
Y00945*
X06305*
Y00944*
Y00943*
X06306*
Y00943*
X06306*
Y00942*
X06307*
Y00942*
X06308*
Y00941*
X06308*
Y00941*
X06309*
Y0094*
X06309*
Y0094*
X0631*
Y00939*
X0631*
Y00939*
X06311*
Y00938*
X06311*
Y00938*
X06312*
Y00937*
X06312*
Y00936*
X06313*
Y00936*
X06314*
Y00935*
X06314*
Y00935*
X06315*
Y00934*
X06315*
Y00934*
X06316*
Y00933*
X06316*
Y00933*
X06317*
Y00932*
X06317*
Y00932*
X06318*
Y00931*
X06318*
Y0093*
X06319*
Y0093*
X06319*
Y00929*
X0632*
Y00929*
X06321*
Y00928*
X06322*
Y00928*
X06324*
Y00927*
X06392*
Y00928*
X06393*
Y00928*
X06394*
Y00929*
Y00929*
X06394*
Y0093*
Y0093*
Y00931*
Y00932*
Y00932*
Y00933*
Y00933*
Y00934*
Y00934*
Y00935*
Y00935*
Y00936*
Y00936*
Y00937*
Y00938*
Y00938*
Y00939*
Y00939*
Y0094*
Y0094*
Y00941*
Y00941*
Y00942*
Y00942*
Y00943*
Y00943*
Y00944*
Y00945*
Y00945*
Y00946*
Y00946*
Y00947*
Y00947*
Y00948*
Y00948*
Y00949*
Y00949*
Y0095*
Y0095*
Y00951*
Y00952*
Y00952*
Y00953*
X06394*
Y00953*
Y00954*
X06393*
Y00954*
X06392*
Y00955*
X06334*
Y00955*
X06334*
Y00956*
Y00956*
Y00957*
Y00958*
Y00958*
Y00959*
Y00959*
Y0096*
Y0096*
Y00961*
Y00961*
Y00962*
Y00962*
Y00963*
Y00963*
Y00964*
Y00965*
Y00965*
Y00966*
Y00966*
Y00967*
Y00967*
Y00968*
Y00968*
Y00969*
Y00969*
Y0097*
Y0097*
Y00971*
Y00972*
Y00972*
Y00973*
Y00973*
Y00974*
X06334*
Y00974*
X06384*
Y00975*
X06385*
Y00975*
Y00976*
X06385*
Y00976*
Y00977*
Y00978*
Y00978*
Y00979*
Y00979*
Y0098*
Y0098*
Y00981*
Y00981*
Y00982*
Y00982*
Y00983*
Y00983*
Y00984*
Y00985*
Y00985*
Y00986*
Y00986*
Y00987*
Y00987*
Y00988*
Y00988*
Y00989*
Y00989*
Y0099*
Y0099*
Y00991*
Y00992*
Y00992*
Y00993*
Y00993*
Y00994*
Y00994*
Y00995*
Y00995*
Y00996*
X06385*
Y00996*
Y00997*
X06384*
Y00998*
X06334*
Y00998*
X06334*
Y00999*
Y00999*
Y01*
Y01*
Y01001*
Y01001*
Y01002*
Y01002*
Y01003*
Y01003*
Y01004*
Y01005*
Y01005*
Y01006*
Y01006*
Y01007*
Y01007*
Y01008*
Y01008*
Y01009*
Y01009*
Y0101*
Y0101*
Y01011*
Y01012*
Y01012*
Y01013*
Y01013*
Y01014*
Y01014*
Y01015*
Y01015*
Y01016*
Y01016*
Y01017*
X06334*
Y01018*
X06392*
Y01018*
X06393*
Y01019*
X06394*
Y01019*
X06394*
Y0102*
Y0102*
Y01021*
Y01021*
Y01022*
Y01022*
Y01023*
Y01023*
Y01024*
Y01025*
Y01025*
Y01026*
Y01026*
Y01027*
Y01027*
Y01028*
Y01028*
Y01029*
Y01029*
Y0103*
Y0103*
Y01031*
Y01032*
Y01032*
Y01033*
Y01033*
Y01034*
Y01034*
Y01035*
Y01035*
Y01036*
Y01036*
Y01037*
Y01038*
Y01038*
Y01039*
Y01039*
Y0104*
Y0104*
Y01041*
Y01041*
Y01042*
Y01042*
X06394*
Y01043*
Y01043*
X06393*
Y01044*
X06392*
Y01045*
X06391*
Y01045*
G37*
G36*
X06115D02*
X06113D01*
Y01045*
X06113*
Y01045*
X0603*
Y01045*
X06028*
Y01044*
X06028*
Y01043*
Y01043*
X06027*
Y01042*
Y01042*
Y01041*
Y01041*
Y0104*
Y0104*
Y01039*
Y01039*
Y01038*
Y01038*
Y01037*
Y01036*
Y01036*
Y01035*
Y01035*
Y01034*
Y01034*
Y01033*
Y01033*
Y01032*
Y01032*
Y01031*
Y0103*
Y0103*
Y01029*
Y01029*
Y01028*
Y01028*
Y01027*
Y01027*
Y01026*
Y01026*
Y01025*
Y01025*
Y01024*
Y01023*
Y01023*
Y01022*
Y01022*
Y01021*
Y01021*
Y0102*
Y0102*
Y01019*
Y01019*
Y01018*
X06028*
Y01018*
X06028*
Y01017*
X06029*
Y01016*
X0603*
Y01016*
X06056*
Y01015*
X06056*
Y01015*
X06057*
Y01014*
Y01014*
X06057*
Y01013*
Y01013*
Y01012*
Y01012*
Y01011*
Y0101*
Y0101*
Y01009*
Y01009*
Y01008*
Y01008*
Y01007*
Y01007*
Y01006*
Y01006*
Y01005*
Y01005*
Y01004*
Y01003*
Y01003*
Y01002*
Y01002*
Y01001*
Y01001*
Y01*
Y01*
Y00999*
Y00999*
Y00998*
Y00998*
Y00997*
Y00996*
Y00996*
Y00995*
Y00995*
Y00994*
Y00994*
Y00993*
Y00993*
Y00992*
Y00992*
Y00991*
Y0099*
Y0099*
Y00989*
Y00989*
Y00988*
Y00988*
Y00987*
Y00987*
Y00986*
Y00986*
Y00985*
Y00985*
Y00984*
Y00983*
Y00983*
Y00982*
Y00982*
Y00981*
Y00981*
Y0098*
Y0098*
Y00979*
Y00979*
Y00978*
Y00978*
Y00977*
Y00976*
Y00976*
Y00975*
Y00975*
Y00974*
Y00974*
Y00973*
Y00973*
Y00972*
Y00972*
Y00971*
Y0097*
Y0097*
Y00969*
Y00969*
Y00968*
Y00968*
Y00967*
Y00967*
Y00966*
Y00966*
Y00965*
Y00965*
Y00964*
Y00963*
Y00963*
Y00962*
Y00962*
Y00961*
Y00961*
Y0096*
Y0096*
Y00959*
Y00959*
Y00958*
Y00958*
Y00957*
Y00956*
Y00956*
Y00955*
Y00955*
Y00954*
Y00954*
Y00953*
Y00953*
Y00952*
Y00952*
Y00951*
Y0095*
Y0095*
Y00949*
Y00949*
Y00948*
Y00948*
Y00947*
Y00947*
Y00946*
Y00946*
Y00945*
Y00945*
Y00944*
Y00943*
Y00943*
Y00942*
Y00942*
Y00941*
Y00941*
Y0094*
Y0094*
Y00939*
Y00939*
Y00938*
Y00938*
Y00937*
Y00936*
Y00936*
Y00935*
Y00935*
Y00934*
Y00934*
Y00933*
Y00933*
Y00932*
Y00932*
Y00931*
Y0093*
Y0093*
Y00929*
Y00929*
X06058*
Y00928*
X06058*
Y00928*
X06059*
Y00927*
X06085*
Y00928*
X06086*
Y00928*
X06086*
Y00929*
Y00929*
Y0093*
X06087*
Y0093*
Y00931*
Y00932*
Y00932*
Y00933*
Y00933*
Y00934*
Y00934*
Y00935*
Y00935*
Y00936*
Y00936*
Y00937*
Y00938*
Y00938*
Y00939*
Y00939*
Y0094*
Y0094*
Y00941*
Y00941*
Y00942*
Y00942*
Y00943*
Y00943*
Y00944*
Y00945*
Y00945*
Y00946*
Y00946*
Y00947*
Y00947*
Y00948*
Y00948*
Y00949*
Y00949*
Y0095*
Y0095*
Y00951*
Y00952*
Y00952*
Y00953*
Y00953*
Y00954*
Y00954*
Y00955*
Y00955*
Y00956*
Y00956*
Y00957*
Y00958*
Y00958*
Y00959*
Y00959*
Y0096*
Y0096*
Y00961*
Y00961*
Y00962*
Y00962*
Y00963*
Y00963*
Y00964*
Y00965*
Y00965*
Y00966*
Y00966*
Y00967*
Y00967*
Y00968*
Y00968*
Y00969*
Y00969*
Y0097*
Y0097*
Y00971*
Y00972*
Y00972*
Y00973*
Y00973*
Y00974*
Y00974*
Y00975*
Y00975*
Y00976*
Y00976*
Y00977*
Y00978*
Y00978*
Y00979*
Y00979*
Y0098*
Y0098*
Y00981*
Y00981*
Y00982*
Y00982*
Y00983*
Y00983*
Y00984*
Y00985*
Y00985*
Y00986*
Y00986*
Y00987*
Y00987*
Y00988*
Y00988*
Y00989*
Y00989*
Y0099*
Y0099*
Y00991*
Y00992*
Y00992*
Y00993*
Y00993*
Y00994*
Y00994*
Y00995*
Y00995*
Y00996*
Y00996*
Y00997*
Y00998*
Y00998*
Y00999*
Y00999*
Y01*
Y01*
Y01001*
Y01001*
Y01002*
Y01002*
Y01003*
Y01003*
Y01004*
Y01005*
Y01005*
Y01006*
Y01006*
Y01007*
Y01007*
Y01008*
Y01008*
Y01009*
Y01009*
Y0101*
Y0101*
Y01011*
Y01012*
Y01012*
Y01013*
Y01013*
Y01014*
Y01014*
Y01015*
X06088*
Y01015*
X06088*
Y01016*
X06114*
Y01016*
X06116*
Y01017*
X06116*
Y01018*
X06117*
Y01018*
Y01019*
Y01019*
X06117*
Y0102*
Y0102*
Y01021*
Y01021*
Y01022*
Y01022*
Y01023*
Y01023*
Y01024*
Y01025*
Y01025*
Y01026*
Y01026*
Y01027*
Y01027*
Y01028*
Y01028*
Y01029*
Y01029*
Y0103*
Y0103*
Y01031*
Y01032*
Y01032*
Y01033*
Y01033*
Y01034*
Y01034*
Y01035*
Y01035*
Y01036*
Y01036*
Y01037*
Y01038*
Y01038*
Y01039*
Y01039*
Y0104*
Y0104*
Y01041*
Y01041*
Y01042*
X06117*
Y01042*
Y01043*
Y01043*
X06116*
Y01044*
X06116*
Y01045*
X06115*
Y01045*
G37*
G36*
X06252D02*
X0617D01*
Y01045*
X06168*
Y01044*
X06168*
Y01043*
Y01043*
X06167*
Y01042*
Y01042*
Y01041*
Y01041*
Y0104*
Y0104*
Y01039*
Y01039*
Y01038*
Y01038*
Y01037*
Y01036*
Y01036*
Y01035*
Y01035*
Y01034*
Y01034*
Y01033*
Y01033*
Y01032*
Y01032*
Y01031*
Y0103*
Y0103*
Y01029*
Y01029*
Y01028*
Y01028*
Y01027*
Y01027*
Y01026*
Y01026*
Y01025*
Y01025*
Y01024*
Y01023*
Y01023*
Y01022*
Y01022*
Y01021*
Y01021*
Y0102*
Y0102*
Y01019*
Y01019*
Y01018*
Y01018*
Y01017*
Y01016*
Y01016*
Y01015*
Y01015*
Y01014*
Y01014*
Y01013*
Y01013*
Y01012*
Y01012*
Y01011*
Y0101*
Y0101*
Y01009*
Y01009*
Y01008*
Y01008*
Y01007*
Y01007*
Y01006*
Y01006*
Y01005*
Y01005*
Y01004*
Y01003*
Y01003*
Y01002*
Y01002*
Y01001*
Y01001*
Y01*
Y01*
Y00999*
Y00999*
Y00998*
Y00998*
Y00997*
Y00996*
Y00996*
Y00995*
Y00995*
Y00994*
Y00994*
Y00993*
Y00993*
Y00992*
Y00992*
Y00991*
Y0099*
Y0099*
Y00989*
Y00989*
Y00988*
Y00988*
Y00987*
Y00987*
Y00986*
Y00986*
Y00985*
Y00985*
Y00984*
Y00983*
Y00983*
Y00982*
Y00982*
Y00981*
Y00981*
Y0098*
Y0098*
Y00979*
Y00979*
Y00978*
Y00978*
Y00977*
Y00976*
Y00976*
Y00975*
Y00975*
Y00974*
Y00974*
Y00973*
Y00973*
Y00972*
Y00972*
Y00971*
Y0097*
Y0097*
Y00969*
Y00969*
Y00968*
Y00968*
Y00967*
Y00967*
Y00966*
Y00966*
Y00965*
Y00965*
Y00964*
Y00963*
Y00963*
Y00962*
Y00962*
Y00961*
Y00961*
Y0096*
Y0096*
Y00959*
Y00959*
Y00958*
Y00958*
Y00957*
Y00956*
Y00956*
Y00955*
Y00955*
Y00954*
Y00954*
Y00953*
Y00953*
Y00952*
Y00952*
Y00951*
Y0095*
Y0095*
Y00949*
Y00949*
Y00948*
Y00948*
Y00947*
Y00947*
Y00946*
Y00946*
Y00945*
Y00945*
Y00944*
Y00943*
Y00943*
Y00942*
Y00942*
Y00941*
Y00941*
Y0094*
Y0094*
Y00939*
Y00939*
Y00938*
Y00938*
Y00937*
Y00936*
Y00936*
Y00935*
Y00935*
Y00934*
Y00934*
Y00933*
Y00933*
Y00932*
Y00932*
Y00931*
Y0093*
Y0093*
Y00929*
Y00929*
X06168*
Y00928*
Y00928*
X06169*
Y00927*
X06195*
Y00928*
X06196*
Y00928*
X06196*
Y00929*
Y00929*
X06197*
Y0093*
Y0093*
Y00931*
Y00932*
Y00932*
Y00933*
Y00933*
Y00934*
Y00934*
Y00935*
Y00935*
Y00936*
Y00936*
Y00937*
Y00938*
Y00938*
Y00939*
Y00939*
Y0094*
Y0094*
Y00941*
Y00941*
Y00942*
Y00942*
Y00943*
Y00943*
Y00944*
Y00945*
Y00945*
Y00946*
Y00946*
Y00947*
Y00947*
Y00948*
Y00948*
Y00949*
Y00949*
Y0095*
Y0095*
Y00951*
Y00952*
Y00952*
Y00953*
Y00953*
Y00954*
Y00954*
Y00955*
Y00955*
Y00956*
Y00956*
Y00957*
Y00958*
Y00958*
Y00959*
Y00959*
Y0096*
Y0096*
Y00961*
Y00961*
Y00962*
Y00962*
Y00963*
Y00963*
Y00964*
Y00965*
Y00965*
Y00966*
Y00966*
Y00967*
Y00967*
Y00968*
Y00968*
Y00969*
Y00969*
Y0097*
Y0097*
Y00971*
Y00972*
Y00972*
Y00973*
Y00973*
Y00974*
Y00974*
Y00975*
Y00975*
Y00976*
Y00976*
Y00977*
Y00978*
Y00978*
Y00979*
Y00979*
Y0098*
Y0098*
Y00981*
Y00981*
Y00982*
Y00982*
Y00983*
Y00983*
Y00984*
Y00985*
Y00985*
Y00986*
Y00986*
Y00987*
Y00987*
Y00988*
Y00988*
Y00989*
Y00989*
Y0099*
Y0099*
Y00991*
Y00992*
Y00992*
Y00993*
Y00993*
Y00994*
Y00994*
Y00995*
Y00995*
Y00996*
Y00996*
Y00997*
Y00998*
Y00998*
Y00999*
Y00999*
Y01*
Y01*
Y01001*
Y01001*
Y01002*
Y01002*
Y01003*
Y01003*
Y01004*
Y01005*
Y01005*
Y01006*
Y01006*
Y01007*
Y01007*
Y01008*
Y01008*
Y01009*
Y01009*
Y0101*
Y0101*
Y01011*
Y01012*
Y01012*
Y01013*
Y01013*
Y01014*
Y01014*
Y01015*
Y01015*
Y01016*
X06215*
Y01015*
Y01015*
Y01014*
Y01014*
Y01013*
Y01013*
Y01012*
Y01012*
Y01011*
Y0101*
Y0101*
Y01009*
Y01009*
Y01008*
Y01008*
Y01007*
Y01007*
Y01006*
Y01006*
Y01005*
Y01005*
Y01004*
Y01003*
Y01003*
Y01002*
Y01002*
Y01001*
Y01001*
Y01*
Y01*
Y00999*
Y00999*
Y00998*
Y00998*
Y00997*
Y00996*
Y00996*
Y00995*
Y00995*
Y00994*
Y00994*
Y00993*
Y00993*
Y00992*
Y00992*
Y00991*
Y0099*
Y0099*
Y00989*
Y00989*
Y00988*
Y00988*
Y00987*
Y00987*
Y00986*
Y00986*
Y00985*
Y00985*
Y00984*
Y00983*
Y00983*
Y00982*
Y00982*
Y00981*
Y00981*
Y0098*
Y0098*
Y00979*
Y00979*
Y00978*
Y00978*
Y00977*
Y00976*
Y00976*
Y00975*
Y00975*
Y00974*
Y00974*
Y00973*
Y00973*
Y00972*
Y00972*
Y00971*
Y0097*
Y0097*
Y00969*
Y00969*
Y00968*
Y00968*
Y00967*
Y00967*
Y00966*
Y00966*
Y00965*
Y00965*
Y00964*
Y00963*
Y00963*
Y00962*
Y00962*
Y00961*
Y00961*
Y0096*
Y0096*
Y00959*
Y00959*
Y00958*
Y00958*
Y00957*
Y00956*
Y00956*
Y00955*
Y00955*
Y00954*
Y00954*
Y00953*
Y00953*
Y00952*
Y00952*
Y00951*
Y0095*
Y0095*
Y00949*
Y00949*
Y00948*
Y00948*
Y00947*
Y00947*
Y00946*
Y00946*
Y00945*
Y00945*
Y00944*
Y00943*
Y00943*
Y00942*
Y00942*
Y00941*
Y00941*
Y0094*
Y0094*
Y00939*
Y00939*
Y00938*
Y00938*
Y00937*
Y00936*
Y00936*
Y00935*
Y00935*
Y00934*
Y00934*
Y00933*
Y00933*
Y00932*
Y00932*
Y00931*
Y0093*
Y0093*
Y00929*
X06216*
Y00929*
Y00928*
X06216*
Y00928*
X06217*
Y00927*
X06241*
Y00928*
X06242*
Y00928*
X06242*
Y00929*
X06243*
Y00929*
Y0093*
Y0093*
Y00931*
Y00932*
Y00932*
Y00933*
Y00933*
Y00934*
Y00934*
Y00935*
Y00935*
Y00936*
Y00936*
Y00937*
Y00938*
Y00938*
Y00939*
Y00939*
Y0094*
Y0094*
Y00941*
Y00941*
Y00942*
Y00942*
Y00943*
Y00943*
Y00944*
Y00945*
Y00945*
Y00946*
Y00946*
Y00947*
Y00947*
Y00948*
Y00948*
Y00949*
Y00949*
Y0095*
Y0095*
Y00951*
Y00952*
Y00952*
Y00953*
Y00953*
Y00954*
Y00954*
Y00955*
Y00955*
Y00956*
Y00956*
Y00957*
Y00958*
Y00958*
Y00959*
Y00959*
Y0096*
Y0096*
Y00961*
Y00961*
Y00962*
Y00962*
Y00963*
Y00963*
Y00964*
Y00965*
Y00965*
Y00966*
Y00966*
Y00967*
Y00967*
Y00968*
Y00968*
Y00969*
Y00969*
Y0097*
Y0097*
Y00971*
Y00972*
Y00972*
Y00973*
Y00973*
Y00974*
Y00974*
Y00975*
Y00975*
Y00976*
Y00976*
Y00977*
Y00978*
Y00978*
Y00979*
Y00979*
Y0098*
Y0098*
Y00981*
Y00981*
Y00982*
Y00982*
Y00983*
Y00983*
Y00984*
Y00985*
Y00985*
Y00986*
Y00986*
Y00987*
Y00987*
Y00988*
Y00988*
Y00989*
Y00989*
Y0099*
Y0099*
Y00991*
Y00992*
Y00992*
Y00993*
Y00993*
Y00994*
Y00994*
Y00995*
Y00995*
Y00996*
Y00996*
Y00997*
Y00998*
Y00998*
Y00999*
Y00999*
Y01*
Y01*
Y01001*
Y01001*
Y01002*
Y01002*
Y01003*
Y01003*
Y01004*
Y01005*
Y01005*
Y01006*
Y01006*
Y01007*
Y01007*
Y01008*
Y01008*
Y01009*
Y01009*
Y0101*
Y0101*
Y01011*
Y01012*
Y01012*
Y01013*
Y01013*
Y01014*
Y01014*
Y01015*
Y01015*
Y01016*
X0625*
Y01016*
X06251*
Y01016*
X06252*
Y01016*
Y01017*
Y01018*
Y01018*
Y01019*
Y01019*
Y0102*
Y0102*
Y01021*
Y01021*
Y01022*
Y01022*
Y01023*
Y01023*
Y01024*
Y01025*
Y01025*
Y01026*
Y01026*
Y01027*
Y01027*
Y01028*
Y01028*
Y01029*
Y01029*
Y0103*
Y0103*
Y01031*
Y01032*
Y01032*
Y01033*
Y01033*
Y01034*
Y01034*
Y01035*
Y01035*
Y01036*
Y01036*
Y01037*
Y01038*
Y01038*
Y01039*
Y01039*
Y0104*
Y0104*
Y01041*
Y01041*
Y01042*
Y01042*
Y01043*
Y01043*
Y01044*
Y01045*
Y01045*
G37*
G36*
X06151D02*
X06126D01*
Y01045*
X06125*
Y01044*
Y01043*
X06124*
Y01043*
Y01042*
X06124*
Y01042*
Y01041*
Y01041*
Y0104*
Y0104*
Y01039*
Y01039*
Y01038*
Y01038*
Y01037*
Y01036*
Y01036*
Y01035*
Y01035*
Y01034*
Y01034*
Y01033*
Y01033*
Y01032*
Y01032*
Y01031*
Y0103*
Y0103*
Y01029*
Y01029*
Y01028*
Y01028*
Y01027*
Y01027*
Y01026*
Y01026*
Y01025*
Y01025*
Y01024*
Y01023*
Y01023*
Y01022*
Y01022*
Y01021*
Y01021*
Y0102*
Y0102*
Y01019*
Y01019*
Y01018*
Y01018*
Y01017*
Y01016*
Y01016*
Y01015*
Y01015*
Y01014*
Y01014*
Y01013*
Y01013*
Y01012*
Y01012*
Y01011*
Y0101*
Y0101*
Y01009*
Y01009*
Y01008*
Y01008*
Y01007*
Y01007*
Y01006*
Y01006*
Y01005*
Y01005*
Y01004*
Y01003*
Y01003*
Y01002*
Y01002*
Y01001*
Y01001*
Y01*
Y01*
Y00999*
Y00999*
Y00998*
Y00998*
Y00997*
Y00996*
Y00996*
Y00995*
Y00995*
Y00994*
Y00994*
Y00993*
Y00993*
Y00992*
Y00992*
Y00991*
Y0099*
Y0099*
Y00989*
Y00989*
Y00988*
Y00988*
Y00987*
Y00987*
Y00986*
Y00986*
Y00985*
Y00985*
Y00984*
Y00983*
Y00983*
Y00982*
Y00982*
Y00981*
Y00981*
Y0098*
Y0098*
Y00979*
Y00979*
Y00978*
Y00978*
Y00977*
Y00976*
Y00976*
Y00975*
Y00975*
Y00974*
Y00974*
Y00973*
Y00973*
Y00972*
Y00972*
Y00971*
Y0097*
Y0097*
Y00969*
Y00969*
Y00968*
Y00968*
Y00967*
Y00967*
Y00966*
Y00966*
Y00965*
Y00965*
Y00964*
Y00963*
Y00963*
Y00962*
Y00962*
Y00961*
Y00961*
Y0096*
Y0096*
Y00959*
Y00959*
Y00958*
Y00958*
Y00957*
Y00956*
Y00956*
Y00955*
Y00955*
Y00954*
Y00954*
Y00953*
Y00953*
Y00952*
Y00952*
Y00951*
Y0095*
Y0095*
Y00949*
Y00949*
Y00948*
Y00948*
Y00947*
Y00947*
Y00946*
Y00946*
Y00945*
Y00945*
Y00944*
Y00943*
Y00943*
Y00942*
Y00942*
Y00941*
Y00941*
Y0094*
Y0094*
Y00939*
Y00939*
Y00938*
Y00938*
Y00937*
Y00936*
Y00936*
Y00935*
Y00935*
Y00934*
Y00934*
Y00933*
Y00933*
Y00932*
Y00932*
Y00931*
Y0093*
Y0093*
Y00929*
X06124*
Y00929*
Y00928*
X06125*
Y00928*
X06125*
Y00927*
X06152*
Y00928*
X06153*
Y00928*
X06153*
Y00929*
Y00929*
Y0093*
Y0093*
Y00931*
Y00932*
Y00932*
Y00933*
Y00933*
Y00934*
Y00934*
Y00935*
Y00935*
Y00936*
Y00936*
Y00937*
Y00938*
Y00938*
Y00939*
Y00939*
Y0094*
Y0094*
Y00941*
Y00941*
Y00942*
Y00942*
Y00943*
Y00943*
Y00944*
Y00945*
Y00945*
Y00946*
Y00946*
Y00947*
Y00947*
Y00948*
Y00948*
Y00949*
Y00949*
Y0095*
Y0095*
Y00951*
Y00952*
Y00952*
Y00953*
Y00953*
Y00954*
Y00954*
Y00955*
Y00955*
Y00956*
Y00956*
Y00957*
Y00958*
Y00958*
Y00959*
Y00959*
Y0096*
Y0096*
Y00961*
Y00961*
Y00962*
Y00962*
Y00963*
Y00963*
Y00964*
Y00965*
Y00965*
Y00966*
Y00966*
Y00967*
Y00967*
Y00968*
Y00968*
Y00969*
Y00969*
Y0097*
Y0097*
Y00971*
Y00972*
Y00972*
Y00973*
Y00973*
Y00974*
Y00974*
Y00975*
Y00975*
Y00976*
Y00976*
Y00977*
Y00978*
Y00978*
Y00979*
Y00979*
Y0098*
Y0098*
Y00981*
Y00981*
Y00982*
Y00982*
Y00983*
Y00983*
Y00984*
Y00985*
Y00985*
Y00986*
Y00986*
Y00987*
Y00987*
Y00988*
Y00988*
Y00989*
Y00989*
Y0099*
Y0099*
Y00991*
Y00992*
Y00992*
Y00993*
Y00993*
Y00994*
Y00994*
Y00995*
Y00995*
Y00996*
Y00996*
Y00997*
Y00998*
Y00998*
Y00999*
Y00999*
Y01*
Y01*
Y01001*
Y01001*
Y01002*
Y01002*
Y01003*
Y01003*
Y01004*
Y01005*
Y01005*
Y01006*
Y01006*
Y01007*
Y01007*
Y01008*
Y01008*
Y01009*
Y01009*
Y0101*
Y0101*
Y01011*
Y01012*
Y01012*
Y01013*
Y01013*
Y01014*
Y01014*
Y01015*
Y01015*
Y01016*
Y01016*
Y01017*
Y01018*
Y01018*
Y01019*
Y01019*
Y0102*
Y0102*
Y01021*
Y01021*
Y01022*
Y01022*
Y01023*
Y01023*
Y01024*
Y01025*
Y01025*
Y01026*
Y01026*
Y01027*
Y01027*
Y01028*
Y01028*
Y01029*
Y01029*
Y0103*
Y0103*
Y01031*
Y01032*
Y01032*
Y01033*
Y01033*
Y01034*
Y01034*
Y01035*
Y01035*
Y01036*
Y01036*
Y01037*
Y01038*
Y01038*
Y01039*
Y01039*
Y0104*
Y0104*
Y01041*
Y01041*
Y01042*
Y01042*
Y01043*
Y01043*
X06153*
Y01044*
X06152*
Y01045*
X06151*
Y01045*
G37*
G36*
X0629Y01132D02*
X0627D01*
Y01132*
X06262*
Y01131*
X06256*
Y01131*
X06252*
Y0113*
X06249*
Y01129*
X06245*
Y01129*
X06242*
Y01128*
X06239*
Y01128*
X06236*
Y01127*
X06233*
Y01127*
X06231*
Y01126*
X06229*
Y01126*
X06227*
Y01125*
X06225*
Y01125*
X06223*
Y01124*
X06221*
Y01123*
X06219*
Y01123*
X06218*
Y01122*
X06216*
Y01122*
X06214*
Y01121*
X06212*
Y01121*
X06211*
Y0112*
X0621*
Y0112*
X06208*
Y01119*
X06206*
Y01119*
X06205*
Y01118*
X06204*
Y01118*
X06202*
Y01117*
X06201*
Y01116*
X06199*
Y01116*
X06198*
Y01115*
X06197*
Y01115*
X06196*
Y01114*
X06195*
Y01114*
X06193*
Y01113*
X06192*
Y01113*
X06191*
Y01112*
X0619*
Y01112*
X06189*
Y01111*
X06188*
Y01111*
X06186*
Y0111*
X06185*
Y01109*
X06184*
Y01109*
X06183*
Y01108*
X06182*
Y01108*
X06181*
Y01107*
X06181*
Y01107*
X06179*
Y01106*
X06178*
Y01106*
X06177*
Y01105*
X06176*
Y01105*
X06176*
Y01104*
X06175*
Y01103*
X06173*
Y01103*
X06173*
Y01102*
X06172*
Y01102*
X06171*
Y01101*
X0617*
Y01101*
X06169*
Y011*
X06168*
Y011*
X06168*
Y01099*
X06166*
Y01099*
X06166*
Y01098*
X06165*
Y01098*
X06164*
Y01097*
X06163*
Y01096*
X06163*
Y01096*
X06162*
Y01095*
X06161*
Y01095*
X0616*
Y01094*
X06159*
Y01094*
X06159*
Y01093*
X06158*
Y01093*
X06157*
Y01092*
X06156*
Y01092*
X06156*
Y01091*
X06155*
Y01091*
X06154*
Y0109*
X06153*
Y01089*
X06153*
Y01089*
X06152*
Y01088*
X06151*
Y01088*
X06151*
Y01087*
X0615*
Y01087*
X06149*
Y01086*
X06149*
Y01086*
X06148*
Y01085*
X06148*
Y01085*
X06146*
Y01084*
X06146*
Y01083*
X06145*
Y01083*
X06145*
Y01082*
X06144*
Y01082*
X06143*
Y01081*
X06143*
Y01081*
X06142*
Y0108*
X06142*
Y0108*
X06141*
Y01079*
X06141*
Y01079*
X0614*
Y01078*
X06139*
Y01078*
X06138*
Y01077*
X06138*
Y01076*
X06137*
Y01076*
X06137*
Y01075*
X06136*
Y01075*
X06136*
Y01074*
X06135*
Y01074*
X06135*
Y01073*
X06134*
Y01073*
X06133*
Y01072*
X06133*
Y01072*
X06132*
Y01071*
X06132*
Y0107*
X06131*
Y0107*
X06131*
Y01069*
X0613*
Y01069*
X0613*
Y01068*
X06129*
Y01068*
X06129*
Y01067*
X06128*
Y01067*
X06128*
Y01066*
X06127*
Y01066*
X06126*
Y01065*
X06126*
Y01065*
X06125*
Y01064*
Y01063*
X06125*
Y01063*
X06124*
Y01062*
X06124*
Y01062*
X06123*
Y01061*
X06123*
Y01061*
X06122*
Y0106*
X06122*
Y0106*
X06121*
Y01059*
Y01059*
X06121*
Y01058*
X0612*
Y01058*
X06119*
Y01057*
X06119*
Y01056*
X06118*
Y01056*
Y01055*
X06118*
Y01055*
X06117*
Y01054*
X06117*
Y01054*
X06125*
Y01054*
X06126*
Y01055*
X06126*
Y01055*
Y01056*
X06127*
Y01056*
X06128*
Y01057*
X06128*
Y01058*
X06129*
Y01058*
X06129*
Y01059*
X0613*
Y01059*
X0613*
Y0106*
X06131*
Y0106*
Y01061*
X06131*
Y01061*
X06132*
Y01062*
X06132*
Y01062*
X06133*
Y01063*
X06133*
Y01063*
X06134*
Y01064*
X06135*
Y01065*
X06135*
Y01065*
X06136*
Y01066*
X06136*
Y01066*
X06137*
Y01067*
X06137*
Y01067*
X06138*
Y01068*
X06138*
Y01068*
X06139*
Y01069*
X06139*
Y01069*
X0614*
Y0107*
X06141*
Y0107*
X06141*
Y01071*
X06142*
Y01072*
X06143*
Y01072*
X06143*
Y01073*
X06144*
Y01073*
X06144*
Y01074*
X06145*
Y01074*
X06145*
Y01075*
X06146*
Y01075*
X06146*
Y01076*
X06147*
Y01076*
X06148*
Y01077*
X06149*
Y01078*
X06149*
Y01078*
X0615*
Y01079*
X0615*
Y01079*
X06151*
Y0108*
X06152*
Y0108*
X06152*
Y01081*
X06153*
Y01081*
X06154*
Y01082*
X06155*
Y01082*
X06155*
Y01083*
X06156*
Y01083*
X06157*
Y01084*
X06157*
Y01085*
X06158*
Y01085*
X06159*
Y01086*
X06159*
Y01086*
X0616*
Y01087*
X06161*
Y01087*
X06162*
Y01088*
X06162*
Y01088*
X06163*
Y01089*
X06164*
Y01089*
X06165*
Y0109*
X06165*
Y01091*
X06166*
Y01091*
X06167*
Y01092*
X06168*
Y01092*
X06169*
Y01093*
X0617*
Y01093*
X0617*
Y01094*
X06171*
Y01094*
X06172*
Y01095*
X06173*
Y01095*
X06174*
Y01096*
X06175*
Y01096*
X06176*
Y01097*
X06177*
Y01098*
X06177*
Y01098*
X06178*
Y01099*
X06179*
Y01099*
X0618*
Y011*
X06181*
Y011*
X06182*
Y01101*
X06183*
Y01101*
X06184*
Y01102*
X06185*
Y01102*
X06186*
Y01103*
X06187*
Y01103*
X06188*
Y01104*
X06189*
Y01105*
X0619*
Y01105*
X06191*
Y01106*
X06193*
Y01106*
X06194*
Y01107*
X06195*
Y01107*
X06196*
Y01108*
X06197*
Y01108*
X06198*
Y01109*
X062*
Y01109*
X06201*
Y0111*
X06202*
Y01111*
X06204*
Y01111*
X06205*
Y01112*
X06206*
Y01112*
X06208*
Y01113*
X06209*
Y01113*
X06211*
Y01114*
X06212*
Y01114*
X06214*
Y01115*
X06215*
Y01115*
X06217*
Y01116*
X06219*
Y01116*
X06221*
Y01117*
X06222*
Y01118*
X06224*
Y01118*
X06226*
Y01119*
X06228*
Y01119*
X0623*
Y0112*
X06232*
Y0112*
X06235*
Y01121*
X06237*
Y01121*
X0624*
Y01122*
X06242*
Y01122*
X06246*
Y01123*
X06249*
Y01123*
X06253*
Y01124*
X06257*
Y01125*
X06263*
Y01125*
X06273*
Y01126*
X06286*
Y01125*
X06287*
Y01126*
X06288*
Y01125*
X06296*
Y01125*
X06302*
Y01124*
X06307*
Y01123*
X0631*
Y01123*
X06314*
Y01122*
X06317*
Y01122*
X06319*
Y01121*
X06322*
Y01121*
X06325*
Y0112*
X06327*
Y0112*
X06329*
Y01119*
X06331*
Y01119*
X06334*
Y01118*
X06335*
Y01118*
X06337*
Y01117*
X06339*
Y01116*
X06341*
Y01116*
X06342*
Y01115*
X06344*
Y01115*
X06345*
Y01114*
X06347*
Y01114*
X06349*
Y01113*
X0635*
Y01113*
X06351*
Y01112*
X06353*
Y01112*
X06354*
Y01111*
X06356*
Y01111*
X06357*
Y0111*
X06358*
Y01109*
X06359*
Y01109*
X06361*
Y01108*
X06362*
Y01108*
X06363*
Y01107*
X06364*
Y01107*
X06365*
Y01106*
X06366*
Y01106*
X06368*
Y01105*
X06369*
Y01105*
X0637*
Y01104*
X06371*
Y01103*
X06372*
Y01103*
X06373*
Y01102*
X06374*
Y01102*
X06375*
Y01101*
X06376*
Y01101*
X06377*
Y011*
X06378*
Y011*
X06379*
Y01099*
X0638*
Y01099*
X06381*
Y01098*
X06382*
Y01098*
X06383*
Y01097*
X06384*
Y01096*
X06385*
Y01096*
X06385*
Y01095*
X06386*
Y01095*
X06388*
Y01094*
X06388*
Y01094*
X06389*
Y01093*
X0639*
Y01093*
X06391*
Y01092*
X06391*
Y01092*
X06392*
Y01091*
X06393*
Y01091*
X06394*
Y0109*
X06395*
Y01089*
X06396*
Y01089*
X06396*
Y01088*
X06397*
Y01088*
X06398*
Y01087*
X06398*
Y01087*
X06399*
Y01086*
X064*
Y01086*
X06401*
Y01085*
X06402*
Y01085*
X06402*
Y01084*
X06403*
Y01083*
X06404*
Y01083*
X06404*
Y01082*
X06405*
Y01082*
X06405*
Y01081*
X06406*
Y01081*
X06407*
Y0108*
X06408*
Y0108*
X06408*
Y01079*
X06409*
Y01079*
X0641*
Y01078*
X0641*
Y01078*
X06411*
Y01077*
X06411*
Y01076*
X06412*
Y01076*
X06413*
Y01075*
X06414*
Y01075*
X06414*
Y01074*
X06415*
Y01074*
X06415*
Y01073*
X06416*
Y01073*
X06416*
Y01072*
X06417*
Y01072*
X06417*
Y01071*
X06418*
Y0107*
X06419*
Y0107*
X06419*
Y01069*
X0642*
Y01069*
X06421*
Y01068*
X06421*
Y01068*
X06422*
Y01067*
X06422*
Y01067*
X06423*
Y01066*
X06423*
Y01066*
X06424*
Y01065*
X06424*
Y01065*
X06425*
Y01064*
X06425*
Y01063*
X06426*
Y01063*
X06427*
Y01062*
X06427*
Y01062*
X06428*
Y01061*
Y01061*
X06428*
Y0106*
X06429*
Y0106*
X06429*
Y01059*
X0643*
Y01059*
X0643*
Y01058*
X06431*
Y01058*
X06431*
Y01057*
X06432*
Y01056*
X06432*
Y01056*
Y01055*
X06433*
Y01055*
X06434*
Y01054*
X06434*
Y01054*
X06435*
Y01053*
X06435*
Y01053*
X06436*
Y01052*
Y01052*
X06436*
Y01051*
X06437*
Y0105*
X06437*
Y0105*
X06438*
Y01049*
Y01049*
X06438*
Y01048*
X06439*
Y01048*
X06439*
Y01047*
X0644*
Y01047*
Y01046*
X06441*
Y01046*
X06441*
Y01045*
X06442*
Y01045*
Y01044*
X06442*
Y01043*
X06443*
Y01043*
X06443*
Y01042*
Y01042*
X06444*
Y01041*
X06444*
Y01041*
Y0104*
X06445*
Y0104*
X06445*
Y01039*
X06446*
Y01039*
Y01038*
X06447*
Y01038*
X06447*
Y01037*
Y01036*
X06448*
Y01036*
X06448*
Y01035*
Y01035*
X06449*
Y01034*
X06449*
Y01034*
Y01033*
X0645*
Y01033*
X0645*
Y01032*
Y01032*
X06451*
Y01031*
X06451*
Y0103*
Y0103*
X06452*
Y01029*
Y01029*
X06452*
Y01028*
X06453*
Y01028*
Y01027*
X06454*
Y01027*
Y01026*
X06454*
Y01026*
X06455*
Y01025*
Y01025*
X06455*
Y01024*
Y01023*
X06456*
Y01023*
Y01022*
X06456*
Y01022*
X06457*
Y01021*
Y01021*
X06457*
Y0102*
Y0102*
X06458*
Y01019*
Y01019*
X06458*
Y01018*
Y01018*
X06459*
Y01017*
Y01016*
X06459*
Y01016*
X0646*
Y01015*
Y01015*
X06461*
Y01014*
Y01014*
X06461*
Y01013*
Y01013*
X06462*
Y01012*
Y01012*
X06462*
Y01011*
Y0101*
Y0101*
X06463*
Y01009*
Y01009*
X06463*
Y01008*
Y01008*
X06464*
Y01007*
Y01007*
X06464*
Y01006*
Y01006*
X06465*
Y01005*
Y01005*
X06465*
Y01004*
Y01003*
Y01003*
X06466*
Y01002*
Y01002*
X06467*
Y01001*
Y01001*
X06467*
Y01*
Y01*
Y00999*
X06468*
Y00999*
Y00998*
X06468*
Y00998*
Y00997*
Y00996*
X06469*
Y00996*
Y00995*
X06469*
Y00995*
Y00994*
Y00994*
X0647*
Y00993*
Y00993*
Y00992*
X0647*
Y00992*
Y00991*
Y0099*
X06471*
Y0099*
Y00989*
X06471*
Y00989*
Y00988*
Y00988*
X06472*
Y00987*
Y00987*
Y00986*
X06472*
Y00986*
Y00985*
Y00985*
Y00984*
X06473*
Y00983*
Y00983*
Y00982*
X06474*
Y00982*
Y00981*
Y00981*
X06474*
Y0098*
Y0098*
Y00979*
Y00979*
X06475*
Y00978*
Y00978*
Y00977*
X06475*
Y00976*
Y00976*
Y00975*
Y00975*
X06476*
Y00974*
Y00974*
Y00973*
Y00973*
X06476*
Y00972*
Y00972*
Y00971*
Y0097*
X06477*
Y0097*
Y00969*
Y00969*
Y00968*
X06477*
Y00968*
Y00967*
Y00967*
Y00966*
Y00966*
X06478*
Y00965*
Y00965*
Y00964*
Y00963*
X06478*
Y00963*
Y00962*
Y00962*
Y00961*
Y00961*
Y0096*
X06479*
Y0096*
Y00959*
Y00959*
Y00958*
Y00958*
X06479*
Y00957*
Y00956*
Y00956*
Y00955*
Y00955*
Y00954*
X0648*
Y00954*
Y00953*
Y00953*
Y00952*
Y00952*
Y00951*
Y0095*
X06481*
Y0095*
Y00949*
Y00949*
Y00948*
Y00948*
Y00947*
Y00947*
Y00946*
Y00946*
X06481*
Y00945*
Y00945*
Y00944*
Y00943*
Y00943*
Y00942*
Y00942*
Y00941*
Y00941*
X06482*
Y0094*
Y0094*
Y00939*
Y00939*
Y00938*
Y00938*
Y00937*
Y00936*
Y00936*
Y00935*
Y00935*
Y00934*
Y00934*
Y00933*
Y00933*
Y00932*
Y00932*
X06482*
Y00931*
Y0093*
Y0093*
Y00929*
Y00929*
Y00928*
Y00928*
Y00927*
Y00927*
Y00926*
Y00926*
X06489*
Y00926*
Y00927*
Y00927*
Y00928*
Y00928*
Y00929*
Y00929*
Y0093*
Y0093*
Y00931*
Y00932*
Y00932*
X06488*
Y00933*
X06489*
Y00933*
Y00934*
Y00934*
X06488*
Y00935*
Y00935*
Y00936*
Y00936*
Y00937*
Y00938*
Y00938*
Y00939*
Y00939*
Y0094*
Y0094*
Y00941*
Y00941*
Y00942*
X06488*
Y00942*
Y00943*
Y00943*
Y00944*
Y00945*
Y00945*
Y00946*
Y00946*
Y00947*
Y00947*
X06487*
Y00948*
Y00948*
Y00949*
Y00949*
Y0095*
Y0095*
Y00951*
Y00952*
X06487*
Y00952*
Y00953*
Y00953*
Y00954*
Y00954*
Y00955*
Y00955*
X06486*
Y00956*
Y00956*
Y00957*
Y00958*
Y00958*
Y00959*
X06485*
Y00959*
Y0096*
Y0096*
Y00961*
Y00961*
X06485*
Y00962*
Y00962*
Y00963*
Y00963*
Y00964*
X06484*
Y00965*
Y00965*
Y00966*
Y00966*
Y00967*
X06484*
Y00967*
Y00968*
Y00968*
Y00969*
Y00969*
X06483*
Y0097*
Y0097*
Y00971*
Y00972*
X06483*
Y00972*
Y00973*
Y00973*
Y00974*
X06482*
Y00974*
Y00975*
Y00975*
Y00976*
X06482*
Y00976*
Y00977*
Y00978*
Y00978*
X06481*
Y00979*
Y00979*
Y0098*
X06481*
Y0098*
Y00981*
Y00981*
Y00982*
X0648*
Y00982*
Y00983*
Y00983*
X06479*
Y00984*
Y00985*
Y00985*
Y00986*
X06479*
Y00986*
Y00987*
Y00987*
X06478*
Y00988*
Y00988*
Y00989*
X06478*
Y00989*
Y0099*
Y0099*
X06477*
Y00991*
Y00992*
Y00992*
X06477*
Y00993*
Y00993*
Y00994*
X06476*
Y00994*
Y00995*
X06476*
Y00995*
Y00996*
Y00996*
X06475*
Y00997*
Y00998*
Y00998*
X06475*
Y00999*
Y00999*
X06474*
Y01*
Y01*
Y01001*
X06474*
Y01001*
Y01002*
X06473*
Y01002*
Y01003*
Y01003*
X06472*
Y01004*
Y01005*
X06472*
Y01005*
Y01006*
X06471*
Y01006*
Y01007*
Y01007*
X06471*
Y01008*
Y01008*
X0647*
Y01009*
Y01009*
X0647*
Y0101*
Y0101*
X06469*
Y01011*
Y01012*
Y01012*
X06469*
Y01013*
Y01013*
X06468*
Y01014*
Y01014*
X06468*
Y01015*
Y01015*
X06467*
Y01016*
Y01016*
X06467*
Y01017*
Y01018*
X06466*
Y01018*
Y01019*
X06465*
Y01019*
Y0102*
X06465*
Y0102*
Y01021*
X06464*
Y01021*
Y01022*
X06464*
Y01022*
X06463*
Y01023*
Y01023*
X06463*
Y01024*
Y01025*
X06462*
Y01025*
Y01026*
X06462*
Y01026*
Y01027*
X06461*
Y01027*
X06461*
Y01028*
Y01028*
X0646*
Y01029*
Y01029*
X06459*
Y0103*
X06459*
Y0103*
Y01031*
X06458*
Y01032*
Y01032*
X06458*
Y01033*
X06457*
Y01033*
Y01034*
X06457*
Y01034*
Y01035*
X06456*
Y01035*
X06456*
Y01036*
Y01036*
X06455*
Y01037*
X06455*
Y01038*
Y01038*
X06454*
Y01039*
X06454*
Y01039*
Y0104*
X06453*
Y0104*
X06452*
Y01041*
Y01041*
X06452*
Y01042*
X06451*
Y01042*
Y01043*
X06451*
Y01043*
X0645*
Y01044*
X0645*
Y01045*
Y01045*
X06449*
Y01046*
X06449*
Y01046*
Y01047*
X06448*
Y01047*
X06448*
Y01048*
X06447*
Y01048*
Y01049*
X06447*
Y01049*
X06446*
Y0105*
X06445*
Y0105*
X06445*
Y01051*
Y01052*
X06444*
Y01052*
X06444*
Y01053*
X06443*
Y01053*
Y01054*
X06443*
Y01054*
X06442*
Y01055*
X06442*
Y01055*
X06441*
Y01056*
X06441*
Y01056*
Y01057*
X0644*
Y01058*
X06439*
Y01058*
X06439*
Y01059*
X06438*
Y01059*
X06438*
Y0106*
Y0106*
X06437*
Y01061*
X06437*
Y01061*
X06436*
Y01062*
X06436*
Y01062*
X06435*
Y01063*
X06435*
Y01063*
X06434*
Y01064*
X06434*
Y01065*
Y01065*
X06433*
Y01066*
X06432*
Y01066*
X06432*
Y01067*
X06431*
Y01067*
X06431*
Y01068*
X0643*
Y01068*
X0643*
Y01069*
X06429*
Y01069*
X06429*
Y0107*
X06428*
Y0107*
X06428*
Y01071*
X06427*
Y01072*
X06427*
Y01072*
X06426*
Y01073*
X06425*
Y01073*
X06425*
Y01074*
X06424*
Y01074*
X06424*
Y01075*
X06423*
Y01075*
X06423*
Y01076*
X06422*
Y01076*
X06421*
Y01077*
X06421*
Y01078*
X0642*
Y01078*
X06419*
Y01079*
X06419*
Y01079*
X06418*
Y0108*
X06418*
Y0108*
X06417*
Y01081*
X06417*
Y01081*
X06416*
Y01082*
X06415*
Y01082*
X06415*
Y01083*
X06414*
Y01083*
X06414*
Y01084*
X06412*
Y01085*
X06412*
Y01085*
X06411*
Y01086*
X06411*
Y01086*
X0641*
Y01087*
X06409*
Y01087*
X06409*
Y01088*
X06408*
Y01088*
X06407*
Y01089*
X06406*
Y01089*
X06406*
Y0109*
X06405*
Y01091*
X06404*
Y01091*
X06404*
Y01092*
X06403*
Y01092*
X06402*
Y01093*
X06402*
Y01093*
X06401*
Y01094*
X064*
Y01094*
X06399*
Y01095*
X06398*
Y01095*
X06398*
Y01096*
X06397*
Y01096*
X06396*
Y01097*
X06395*
Y01098*
X06395*
Y01098*
X06394*
Y01099*
X06393*
Y01099*
X06392*
Y011*
X06391*
Y011*
X0639*
Y01101*
X06389*
Y01101*
X06389*
Y01102*
X06388*
Y01102*
X06386*
Y01103*
X06386*
Y01103*
X06385*
Y01104*
X06384*
Y01105*
X06383*
Y01105*
X06382*
Y01106*
X06381*
Y01106*
X0638*
Y01107*
X06379*
Y01107*
X06378*
Y01108*
X06377*
Y01108*
X06376*
Y01109*
X06375*
Y01109*
X06374*
Y0111*
X06372*
Y01111*
X06371*
Y01111*
X06371*
Y01112*
X0637*
Y01112*
X06368*
Y01113*
X06367*
Y01113*
X06366*
Y01114*
X06365*
Y01114*
X06364*
Y01115*
X06362*
Y01115*
X06361*
Y01116*
X0636*
Y01116*
X06358*
Y01117*
X06357*
Y01118*
X06356*
Y01118*
X06354*
Y01119*
X06353*
Y01119*
X06351*
Y0112*
X0635*
Y0112*
X06348*
Y01121*
X06347*
Y01121*
X06345*
Y01122*
X06344*
Y01122*
X06342*
Y01123*
X0634*
Y01123*
X06338*
Y01124*
X06336*
Y01125*
X06335*
Y01125*
X06332*
Y01126*
X0633*
Y01126*
X06328*
Y01127*
X06326*
Y01127*
X06323*
Y01128*
X06321*
Y01128*
X06318*
Y01129*
X06315*
Y01129*
X06311*
Y0113*
X06307*
Y01131*
X06303*
Y01131*
X06298*
Y01132*
X0629*
Y01132*
G37*
G36*
X06214Y00918D02*
X06213D01*
Y00917*
X06212*
Y00918*
X06148*
Y00917*
X06146*
Y00916*
X06144*
Y00916*
X06143*
Y00915*
X06143*
Y00915*
X06142*
Y00914*
X06142*
Y00914*
X06141*
Y00913*
X06141*
Y00913*
X0614*
Y00912*
X06139*
Y00912*
X06139*
Y00911*
X06138*
Y0091*
X06138*
Y0091*
X06137*
Y00909*
X06137*
Y00909*
X06136*
Y00908*
X06136*
Y00908*
X06135*
Y00907*
X06135*
Y00907*
X06134*
Y00906*
X06133*
Y00906*
X06133*
Y00905*
X06132*
Y00905*
X06132*
Y00904*
X06131*
Y00903*
X06131*
Y00903*
X0613*
Y00902*
X0613*
Y00902*
X06129*
Y00901*
X06129*
Y00901*
X06128*
Y009*
Y009*
X06128*
Y00899*
Y00899*
Y00898*
Y00897*
X06127*
Y00897*
Y00896*
Y00896*
Y00895*
Y00895*
Y00894*
Y00894*
Y00893*
Y00893*
Y00892*
Y00892*
Y00891*
Y0089*
Y0089*
Y00889*
Y00889*
Y00888*
Y00888*
Y00887*
Y00887*
Y00886*
Y00886*
Y00885*
Y00885*
Y00884*
Y00883*
Y00883*
Y00882*
Y00882*
Y00881*
Y00881*
Y0088*
Y0088*
Y00879*
Y00879*
Y00878*
Y00877*
Y00877*
Y00876*
Y00876*
Y00875*
Y00875*
Y00874*
Y00874*
Y00873*
Y00873*
Y00872*
Y00872*
Y00871*
Y0087*
Y0087*
Y00869*
Y00869*
Y00868*
Y00868*
Y00867*
Y00867*
Y00866*
Y00866*
Y00865*
Y00865*
Y00864*
Y00863*
Y00863*
Y00862*
Y00862*
Y00861*
Y00861*
Y0086*
Y0086*
Y00859*
Y00859*
Y00858*
Y00857*
Y00857*
Y00856*
Y00856*
Y00855*
Y00855*
Y00854*
Y00854*
Y00853*
Y00853*
Y00852*
Y00852*
Y00851*
Y0085*
Y0085*
Y00849*
Y00849*
Y00848*
Y00848*
Y00847*
Y00847*
Y00846*
Y00846*
Y00845*
Y00845*
Y00844*
Y00843*
Y00843*
Y00842*
Y00842*
Y00841*
Y00841*
Y0084*
Y0084*
Y00839*
Y00839*
Y00838*
Y00837*
Y00837*
Y00836*
Y00836*
Y00835*
Y00835*
Y00834*
Y00834*
Y00833*
Y00833*
Y00832*
Y00832*
Y00831*
Y0083*
Y0083*
Y00829*
Y00829*
Y00828*
Y00828*
Y00827*
Y00827*
Y00826*
Y00826*
Y00825*
Y00825*
Y00824*
Y00823*
Y00823*
Y00822*
Y00822*
Y00821*
Y00821*
Y0082*
Y0082*
Y00819*
X06128*
Y00819*
Y00818*
Y00817*
X06128*
Y00817*
Y00816*
X06129*
Y00816*
X06129*
Y00815*
X0613*
Y00815*
X0613*
Y00814*
X06131*
Y00814*
X06131*
Y00813*
X06132*
Y00813*
X06132*
Y00812*
X06133*
Y00812*
X06133*
Y00811*
X06134*
Y0081*
X06135*
Y0081*
X06135*
Y00809*
X06136*
Y00809*
X06136*
Y00808*
X06137*
Y00808*
X06137*
Y00807*
X06138*
Y00807*
X06138*
Y00806*
X06139*
Y00806*
X06139*
Y00805*
X0614*
Y00805*
X06141*
Y00804*
X06141*
Y00803*
X06142*
Y00803*
X06142*
Y00802*
X06143*
Y00802*
X06143*
Y00801*
X06144*
Y00801*
X06145*
Y008*
X06146*
Y008*
X06215*
Y008*
X06216*
Y00801*
X06216*
Y00801*
X06217*
Y00802*
Y00802*
Y00803*
Y00803*
Y00804*
Y00805*
Y00805*
Y00806*
Y00806*
Y00807*
Y00807*
Y00808*
Y00808*
Y00809*
Y00809*
Y0081*
Y0081*
Y00811*
Y00812*
Y00812*
Y00813*
Y00813*
Y00814*
Y00814*
Y00815*
Y00815*
Y00816*
Y00816*
Y00817*
Y00817*
Y00818*
Y00819*
Y00819*
Y0082*
Y0082*
Y00821*
Y00821*
Y00822*
Y00822*
Y00823*
Y00823*
Y00824*
Y00825*
Y00825*
Y00826*
Y00826*
Y00827*
X06216*
Y00827*
X06216*
Y00828*
X06215*
Y00828*
X06158*
Y00829*
X06157*
Y00829*
Y0083*
X06157*
Y0083*
Y00831*
Y00832*
Y00832*
Y00833*
Y00833*
Y00834*
Y00834*
Y00835*
Y00835*
Y00836*
Y00836*
Y00837*
Y00837*
Y00838*
Y00839*
Y00839*
Y0084*
Y0084*
Y00841*
Y00841*
Y00842*
Y00842*
Y00843*
Y00843*
Y00844*
Y00845*
Y00845*
Y00846*
Y00846*
Y00847*
Y00847*
Y00848*
Y00848*
Y00849*
Y00849*
Y0085*
Y0085*
Y00851*
Y00852*
Y00852*
Y00853*
Y00853*
Y00854*
Y00854*
Y00855*
Y00855*
Y00856*
Y00856*
Y00857*
Y00857*
Y00858*
Y00859*
Y00859*
Y0086*
Y0086*
Y00861*
Y00861*
Y00862*
Y00862*
Y00863*
Y00863*
Y00864*
Y00865*
Y00865*
Y00866*
Y00866*
Y00867*
Y00867*
Y00868*
Y00868*
Y00869*
Y00869*
Y0087*
Y0087*
Y00871*
Y00872*
Y00872*
Y00873*
Y00873*
Y00874*
Y00874*
Y00875*
Y00875*
Y00876*
Y00876*
Y00877*
Y00877*
Y00878*
Y00879*
Y00879*
Y0088*
Y0088*
Y00881*
Y00881*
Y00882*
Y00882*
Y00883*
Y00883*
Y00884*
Y00885*
Y00885*
Y00886*
Y00886*
Y00887*
Y00887*
X06157*
Y00888*
X06158*
Y00888*
X06211*
Y00889*
X06212*
Y00888*
X06214*
Y00889*
X06216*
Y00889*
X06216*
Y0089*
X06217*
Y0089*
Y00891*
Y00892*
Y00892*
Y00893*
Y00893*
Y00894*
Y00894*
Y00895*
Y00895*
Y00896*
Y00896*
Y00897*
Y00897*
Y00898*
Y00899*
Y00899*
Y009*
Y009*
Y00901*
Y00901*
Y00902*
Y00902*
Y00903*
Y00903*
Y00904*
Y00905*
Y00905*
Y00906*
Y00906*
Y00907*
Y00907*
Y00908*
Y00908*
Y00909*
Y00909*
Y0091*
Y0091*
Y00911*
Y00912*
Y00912*
Y00913*
Y00913*
Y00914*
Y00914*
Y00915*
Y00915*
Y00916*
X06216*
Y00916*
X06216*
Y00917*
X06214*
Y00918*
G37*
G36*
X06309D02*
X06301D01*
Y00917*
X06301*
Y00916*
X063*
Y00916*
X06299*
Y00915*
X06299*
Y00915*
X06298*
Y00914*
X06298*
Y00914*
X06297*
Y00913*
X06297*
Y00913*
X06296*
Y00912*
X06296*
Y00912*
X06295*
Y00911*
X06295*
Y0091*
X06294*
Y0091*
X06294*
Y00909*
X06293*
Y00909*
X06292*
Y00908*
X06292*
Y00908*
X06291*
Y00907*
X06291*
Y00907*
X0629*
Y00906*
X0629*
Y00906*
X06289*
Y00905*
X06289*
Y00905*
X06288*
Y00904*
X06288*
Y00903*
X06287*
Y00903*
X06286*
Y00902*
X06286*
Y00902*
X06285*
Y00901*
X06285*
Y00901*
X06284*
Y009*
X06284*
Y009*
X06283*
Y00899*
X06283*
Y00899*
X06282*
Y00898*
X06282*
Y00897*
X06281*
Y00897*
X06281*
Y00896*
X0628*
Y00896*
X06279*
Y00895*
X06279*
Y00895*
X06278*
Y00894*
X06278*
Y00894*
X06277*
Y00893*
X06277*
Y00893*
X06276*
Y00892*
X06276*
Y00892*
X06275*
Y00891*
X06299*
Y0089*
Y0089*
Y00889*
Y00889*
Y00888*
Y00888*
Y00887*
Y00887*
Y00886*
Y00886*
Y00885*
Y00885*
Y00884*
Y00883*
Y00883*
Y00882*
Y00882*
Y00881*
Y00881*
Y0088*
Y0088*
Y00879*
Y00879*
Y00878*
Y00877*
Y00877*
Y00876*
Y00876*
Y00875*
Y00875*
Y00874*
Y00874*
Y00873*
Y00873*
Y00872*
Y00872*
Y00871*
Y0087*
Y0087*
Y00869*
Y00869*
Y00868*
Y00868*
Y00867*
Y00867*
Y00866*
Y00866*
Y00865*
Y00865*
Y00864*
Y00863*
Y00863*
Y00862*
Y00862*
Y00861*
X0626*
Y00862*
Y00862*
Y00863*
Y00863*
Y00864*
Y00865*
Y00865*
Y00866*
Y00866*
Y00867*
Y00867*
Y00868*
Y00868*
Y00869*
Y00869*
Y0087*
Y0087*
Y00871*
Y00872*
Y00872*
Y00873*
Y00873*
X06259*
Y00873*
X06259*
Y00872*
X06258*
Y00872*
X06258*
Y00871*
X06257*
Y0087*
X06257*
Y0087*
X06256*
Y00869*
X06256*
Y00869*
X06255*
Y00868*
X06255*
Y00868*
X06254*
Y00867*
X06254*
Y00867*
X06253*
Y00866*
X06252*
Y00866*
X06252*
Y00865*
X06251*
Y00865*
X06251*
Y00864*
X0625*
Y00863*
X0625*
Y00863*
X06249*
Y00862*
X06249*
Y00862*
X06248*
Y00861*
X06248*
Y00861*
X06247*
Y0086*
X06246*
Y0086*
X06246*
Y00859*
X06245*
Y00859*
X06245*
Y00858*
X06244*
Y00857*
X06244*
Y00857*
X06243*
Y00856*
X06243*
Y00856*
X06242*
Y00855*
X06242*
Y00855*
X06241*
Y00854*
X06241*
Y00854*
X0624*
Y00853*
X06239*
Y00853*
X06239*
Y00852*
X06238*
Y00852*
X06238*
Y00851*
X06237*
Y0085*
X06237*
Y0085*
X06236*
Y00849*
X06236*
Y00849*
X06235*
Y00848*
X06235*
Y00848*
X06233*
Y00847*
X06233*
Y00847*
X06232*
Y00846*
X06232*
Y00846*
X06231*
Y00845*
X06231*
Y00845*
X0623*
Y00844*
Y00843*
Y00843*
Y00842*
Y00842*
Y00841*
Y00841*
Y0084*
Y0084*
Y00839*
Y00839*
Y00838*
Y00837*
Y00837*
Y00836*
Y00836*
Y00835*
Y00835*
Y00834*
Y00834*
Y00833*
Y00833*
Y00832*
Y00832*
Y00831*
Y0083*
Y0083*
Y00829*
Y00829*
Y00828*
Y00828*
Y00827*
Y00827*
Y00826*
Y00826*
Y00825*
Y00825*
Y00824*
Y00823*
Y00823*
Y00822*
Y00822*
Y00821*
Y00821*
Y0082*
Y0082*
Y00819*
Y00819*
Y00818*
Y00817*
Y00817*
Y00816*
Y00816*
Y00815*
Y00815*
Y00814*
Y00814*
Y00813*
Y00813*
Y00812*
Y00812*
Y00811*
Y0081*
Y0081*
Y00809*
Y00809*
Y00808*
Y00808*
Y00807*
Y00807*
Y00806*
Y00806*
Y00805*
Y00805*
Y00804*
Y00803*
Y00803*
Y00802*
Y00802*
Y00801*
X06231*
Y00801*
X06231*
Y008*
X06232*
Y008*
X06258*
Y008*
X06259*
Y00801*
X06259*
Y00801*
Y00802*
X0626*
Y00802*
Y00803*
Y00803*
Y00804*
Y00805*
Y00805*
Y00806*
Y00806*
Y00807*
Y00807*
Y00808*
Y00808*
Y00809*
Y00809*
Y0081*
Y0081*
Y00811*
Y00812*
Y00812*
Y00813*
Y00813*
Y00814*
Y00814*
Y00815*
Y00815*
Y00816*
Y00816*
Y00817*
Y00817*
Y00818*
Y00819*
Y00819*
Y0082*
Y0082*
Y00821*
Y00821*
Y00822*
Y00822*
Y00823*
Y00823*
Y00824*
Y00825*
Y00825*
Y00826*
Y00826*
Y00827*
Y00827*
Y00828*
Y00828*
Y00829*
Y00829*
Y0083*
Y0083*
Y00831*
Y00832*
Y00832*
Y00833*
Y00833*
Y00834*
Y00834*
X06261*
Y00835*
Y00835*
X06262*
Y00836*
X06298*
Y00835*
X06299*
Y00835*
Y00834*
X06299*
Y00834*
Y00833*
Y00833*
Y00832*
Y00832*
Y00831*
Y0083*
Y0083*
Y00829*
Y00829*
Y00828*
Y00828*
Y00827*
Y00827*
Y00826*
Y00826*
Y00825*
Y00825*
Y00824*
Y00823*
Y00823*
Y00822*
Y00822*
Y00821*
Y00821*
Y0082*
Y0082*
Y00819*
Y00819*
Y00818*
Y00817*
Y00817*
Y00816*
Y00816*
Y00815*
Y00815*
Y00814*
Y00814*
Y00813*
Y00813*
Y00812*
Y00812*
Y00811*
Y0081*
Y0081*
Y00809*
Y00809*
Y00808*
Y00808*
Y00807*
Y00807*
Y00806*
Y00806*
Y00805*
Y00805*
Y00804*
Y00803*
Y00803*
Y00802*
Y00802*
Y00801*
X063*
Y00801*
X06301*
Y008*
X06302*
Y008*
X06327*
Y008*
X06328*
Y00801*
X06329*
Y00801*
Y00802*
X06329*
Y00802*
Y00803*
Y00803*
Y00804*
Y00805*
Y00805*
Y00806*
Y00806*
Y00807*
Y00807*
Y00808*
Y00808*
Y00809*
Y00809*
Y0081*
Y0081*
Y00811*
Y00812*
Y00812*
Y00813*
Y00813*
Y00814*
Y00814*
Y00815*
Y00815*
Y00816*
Y00816*
Y00817*
Y00817*
Y00818*
Y00819*
Y00819*
Y0082*
Y0082*
Y00821*
Y00821*
Y00822*
Y00822*
Y00823*
Y00823*
Y00824*
Y00825*
Y00825*
Y00826*
Y00826*
Y00827*
Y00827*
Y00828*
Y00828*
Y00829*
Y00829*
Y0083*
Y0083*
Y00831*
Y00832*
Y00832*
Y00833*
Y00833*
Y00834*
Y00834*
Y00835*
Y00835*
Y00836*
Y00836*
Y00837*
Y00837*
Y00838*
Y00839*
Y00839*
Y0084*
Y0084*
Y00841*
Y00841*
Y00842*
Y00842*
Y00843*
Y00843*
Y00844*
Y00845*
Y00845*
Y00846*
Y00846*
Y00847*
Y00847*
Y00848*
Y00848*
Y00849*
Y00849*
Y0085*
Y0085*
Y00851*
Y00852*
Y00852*
Y00853*
Y00853*
Y00854*
Y00854*
Y00855*
Y00855*
Y00856*
Y00856*
Y00857*
Y00857*
Y00858*
Y00859*
Y00859*
Y0086*
Y0086*
Y00861*
Y00861*
Y00862*
Y00862*
Y00863*
Y00863*
Y00864*
Y00865*
Y00865*
Y00866*
Y00866*
Y00867*
Y00867*
Y00868*
Y00868*
Y00869*
Y00869*
Y0087*
Y0087*
Y00871*
Y00872*
Y00872*
Y00873*
Y00873*
Y00874*
Y00874*
Y00875*
Y00875*
Y00876*
Y00876*
Y00877*
Y00877*
Y00878*
Y00879*
Y00879*
Y0088*
Y0088*
Y00881*
Y00881*
Y00882*
Y00882*
Y00883*
Y00883*
Y00884*
Y00885*
Y00885*
Y00886*
Y00886*
Y00887*
Y00887*
Y00888*
Y00888*
Y00889*
Y00889*
Y0089*
Y0089*
Y00891*
Y00892*
Y00892*
Y00893*
Y00893*
Y00894*
Y00894*
Y00895*
Y00895*
Y00896*
Y00896*
Y00897*
X06329*
Y00897*
Y00898*
Y00899*
Y00899*
X06328*
Y009*
Y009*
Y00901*
X06328*
Y00901*
X06327*
Y00902*
X06326*
Y00902*
X06326*
Y00903*
X06325*
Y00903*
X06325*
Y00904*
X06324*
Y00905*
X06324*
Y00905*
X06323*
Y00906*
X06323*
Y00906*
X06322*
Y00907*
X06322*
Y00907*
X06321*
Y00908*
X06321*
Y00908*
X0632*
Y00909*
X06319*
Y00909*
X06319*
Y0091*
X06318*
Y0091*
X06318*
Y00911*
X06317*
Y00912*
X06317*
Y00912*
X06316*
Y00913*
X06316*
Y00913*
X06315*
Y00914*
X06315*
Y00914*
X06314*
Y00915*
X06314*
Y00915*
X06313*
Y00916*
X06312*
Y00916*
X06311*
Y00917*
X06309*
Y00918*
G37*
G36*
X06271Y01109D02*
X06262D01*
Y01109*
Y01108*
Y01108*
Y01107*
Y01107*
Y01106*
Y01106*
Y01105*
Y01105*
Y01104*
Y01103*
Y01103*
Y01102*
Y01102*
Y01101*
Y01101*
Y011*
Y011*
Y01099*
Y01099*
Y01098*
Y01098*
Y01097*
Y01096*
Y01096*
Y01095*
Y01095*
Y01094*
Y01094*
Y01093*
Y01093*
Y01092*
Y01092*
Y01091*
Y01091*
Y0109*
Y01089*
Y01089*
Y01088*
Y01088*
Y01087*
Y01087*
Y01086*
Y01086*
Y01085*
Y01085*
Y01084*
Y01083*
Y01083*
Y01082*
Y01082*
Y01081*
Y01081*
Y0108*
Y0108*
Y01079*
Y01079*
Y01078*
Y01078*
Y01077*
Y01076*
Y01076*
Y01075*
Y01075*
Y01074*
Y01074*
Y01073*
Y01073*
Y01072*
Y01072*
Y01071*
Y0107*
Y0107*
Y01069*
Y01069*
Y01068*
Y01068*
Y01067*
Y01067*
Y01066*
Y01066*
Y01065*
Y01065*
Y01064*
Y01063*
Y01063*
Y01062*
Y01062*
Y01061*
Y01061*
Y0106*
Y0106*
Y01059*
Y01059*
Y01058*
Y01058*
Y01057*
Y01056*
Y01056*
Y01055*
Y01055*
Y01054*
Y01054*
Y01053*
Y01053*
Y01052*
Y01052*
Y01051*
Y0105*
Y0105*
Y01049*
Y01049*
Y01048*
Y01048*
Y01047*
Y01047*
Y01046*
Y01046*
Y01045*
Y01045*
Y01044*
Y01043*
Y01043*
Y01042*
Y01042*
Y01041*
Y01041*
Y0104*
Y0104*
Y01039*
Y01039*
Y01038*
Y01038*
Y01037*
Y01036*
Y01036*
Y01035*
Y01035*
Y01034*
Y01034*
Y01033*
Y01033*
Y01032*
Y01032*
Y01031*
Y0103*
Y0103*
Y01029*
Y01029*
Y01028*
Y01028*
Y01027*
Y01027*
Y01026*
Y01026*
Y01025*
Y01025*
Y01024*
Y01023*
Y01023*
Y01022*
Y01022*
Y01021*
Y01021*
Y0102*
Y0102*
Y01019*
Y01019*
Y01018*
Y01018*
Y01017*
Y01016*
Y01016*
Y01015*
Y01015*
Y01014*
Y01014*
Y01013*
Y01013*
Y01012*
Y01012*
Y01011*
Y0101*
Y0101*
Y01009*
Y01009*
Y01008*
Y01008*
Y01007*
Y01007*
Y01006*
Y01006*
Y01005*
Y01005*
Y01004*
Y01003*
Y01003*
Y01002*
Y01002*
Y01001*
Y01001*
Y01*
Y01*
Y00999*
Y00999*
Y00998*
Y00998*
Y00997*
Y00996*
Y00996*
Y00995*
Y00995*
Y00994*
Y00994*
Y00993*
Y00993*
Y00992*
Y00992*
Y00991*
Y0099*
Y0099*
Y00989*
Y00989*
Y00988*
Y00988*
Y00987*
Y00987*
Y00986*
Y00986*
Y00985*
Y00985*
Y00984*
Y00983*
Y00983*
Y00982*
Y00982*
Y00981*
Y00981*
Y0098*
Y0098*
Y00979*
Y00979*
Y00978*
Y00978*
Y00977*
Y00976*
Y00976*
Y00975*
Y00975*
Y00974*
Y00974*
Y00973*
Y00973*
Y00972*
Y00972*
Y00971*
Y0097*
Y0097*
Y00969*
Y00969*
Y00968*
Y00968*
Y00967*
Y00967*
Y00966*
Y00966*
Y00965*
Y00965*
Y00964*
Y00963*
Y00963*
Y00962*
Y00962*
Y00961*
Y00961*
Y0096*
Y0096*
Y00959*
Y00959*
Y00958*
Y00958*
Y00957*
Y00956*
Y00956*
Y00955*
Y00955*
Y00954*
Y00954*
Y00953*
Y00953*
Y00952*
Y00952*
Y00951*
Y0095*
Y0095*
Y00949*
Y00949*
Y00948*
Y00948*
Y00947*
Y00947*
Y00946*
Y00946*
Y00945*
Y00945*
Y00944*
Y00943*
Y00943*
Y00942*
Y00942*
Y00941*
Y00941*
Y0094*
Y0094*
Y00939*
Y00939*
Y00938*
Y00938*
Y00937*
Y00936*
Y00936*
Y00935*
Y00935*
Y00934*
Y00934*
Y00933*
Y00933*
Y00932*
Y00932*
Y00931*
Y0093*
X06261*
Y0093*
X06261*
Y00929*
X0626*
Y00929*
X06259*
Y00928*
X06259*
Y00928*
X06258*
Y00927*
X06258*
Y00927*
X06257*
Y00926*
X06257*
Y00926*
X06256*
Y00925*
X06256*
Y00925*
X06255*
Y00924*
X06255*
Y00923*
X06254*
Y00923*
X06254*
Y00922*
X06253*
Y00922*
X06252*
Y00921*
X06251*
Y00921*
X06251*
Y0092*
X0625*
Y0092*
X0625*
Y00919*
X06249*
Y00919*
X06249*
Y00918*
X06248*
Y00918*
X06248*
Y00917*
X06247*
Y00916*
X06246*
Y00916*
X06246*
Y00915*
X06245*
Y00915*
X06245*
Y00914*
X06244*
Y00914*
X06244*
Y00913*
X06243*
Y00913*
X06243*
Y00912*
X06242*
Y00912*
X06242*
Y00911*
X06241*
Y0091*
X06241*
Y0091*
X0624*
Y00909*
X06239*
Y00909*
X06239*
Y00908*
X06238*
Y00908*
X06238*
Y00907*
X06237*
Y00907*
X06237*
Y00906*
X06236*
Y00906*
X06236*
Y00905*
X06235*
Y00905*
X06235*
Y00904*
X06234*
Y00903*
X06233*
Y00903*
X06233*
Y00902*
X06232*
Y00902*
X06232*
Y00901*
X06231*
Y00901*
X06231*
Y009*
X0623*
Y009*
X0623*
Y00899*
X06229*
Y00899*
X06229*
Y00898*
X06228*
Y00897*
X06228*
Y00897*
X06227*
Y00896*
X06226*
Y00896*
X06226*
Y00895*
X06225*
Y00895*
X06225*
Y00894*
X06224*
Y00894*
X06224*
Y00893*
X06223*
Y00893*
X06223*
Y00892*
X06222*
Y00892*
X06222*
Y00891*
X06221*
Y0089*
X06221*
Y0089*
X0622*
Y00889*
X06219*
Y00889*
X06219*
Y00888*
X06218*
Y00888*
X06218*
Y00887*
X06217*
Y00887*
X06217*
Y00886*
X06216*
Y00886*
X06216*
Y00885*
X06215*
Y00885*
X06214*
Y00884*
X06213*
Y00883*
X06213*
Y00883*
X06212*
Y00882*
X06212*
Y00882*
X06211*
Y00881*
X06211*
Y00881*
X0621*
Y0088*
X0621*
Y0088*
X06209*
Y00879*
X06209*
Y00879*
X06208*
Y00878*
X06208*
Y00877*
X06207*
Y00877*
X06206*
Y00876*
X06206*
Y00876*
Y00875*
X06205*
Y00875*
X06205*
Y00874*
Y00874*
X06204*
Y00873*
Y00873*
X06204*
Y00872*
Y00872*
Y00871*
Y0087*
Y0087*
Y00869*
Y00869*
Y00868*
Y00868*
Y00867*
Y00867*
Y00866*
Y00866*
Y00865*
Y00865*
Y00864*
Y00863*
Y00863*
Y00862*
Y00862*
Y00861*
Y00861*
Y0086*
Y0086*
Y00859*
Y00859*
Y00858*
Y00857*
Y00857*
Y00856*
Y00856*
Y00855*
Y00855*
Y00854*
Y00854*
Y00853*
Y00853*
Y00852*
Y00852*
Y00851*
Y0085*
Y0085*
Y00849*
Y00849*
Y00848*
X06204*
Y00848*
X06205*
Y00847*
Y00847*
X06205*
Y00846*
X06206*
Y00846*
Y00845*
X06206*
Y00845*
X06207*
Y00844*
X06208*
Y00843*
X06208*
Y00843*
X06209*
Y00842*
X06209*
Y00842*
X0621*
Y00841*
X0621*
Y00841*
X06211*
Y0084*
X06212*
Y00841*
X06212*
Y00841*
X06213*
Y00842*
X06213*
Y00842*
X06214*
Y00843*
X06215*
Y00843*
X06215*
Y00844*
X06216*
Y00845*
X06216*
Y00845*
X06217*
Y00846*
X06217*
Y00846*
X06218*
Y00847*
X06218*
Y00847*
X06219*
Y00848*
X06219*
Y00848*
X0622*
Y00849*
X06221*
Y00849*
X06221*
Y0085*
X06222*
Y0085*
X06222*
Y00851*
X06223*
Y00852*
X06223*
Y00852*
X06224*
Y00853*
X06224*
Y00853*
X06225*
Y00854*
X06226*
Y00854*
X06226*
Y00855*
X06227*
Y00855*
X06228*
Y00856*
X06228*
Y00856*
X06229*
Y00857*
X06229*
Y00857*
X0623*
Y00858*
X0623*
Y00859*
X06231*
Y00859*
X06231*
Y0086*
X06232*
Y0086*
X06232*
Y00861*
X06233*
Y00861*
X06233*
Y00862*
X06234*
Y00862*
X06235*
Y00863*
X06235*
Y00863*
X06236*
Y00864*
X06236*
Y00865*
X06237*
Y00865*
X06237*
Y00866*
X06238*
Y00866*
X06238*
Y00867*
X06239*
Y00867*
X06239*
Y00868*
X0624*
Y00868*
X06241*
Y00869*
X06241*
Y00869*
X06242*
Y0087*
X06242*
Y0087*
X06243*
Y00871*
X06243*
Y00872*
X06244*
Y00872*
X06244*
Y00873*
X06245*
Y00873*
X06245*
Y00874*
X06246*
Y00874*
X06246*
Y00875*
X06247*
Y00875*
X06248*
Y00876*
X06248*
Y00876*
X06249*
Y00877*
X06249*
Y00877*
X0625*
Y00878*
X0625*
Y00879*
X06251*
Y00879*
X06251*
Y0088*
X06252*
Y0088*
X06252*
Y00881*
X06253*
Y00881*
X06254*
Y00882*
X06254*
Y00882*
X06255*
Y00883*
X06255*
Y00883*
X06256*
Y00884*
X06256*
Y00885*
X06257*
Y00885*
X06257*
Y00886*
X06258*
Y00886*
X06258*
Y00887*
X06259*
Y00887*
X06259*
Y00888*
X0626*
Y00888*
X06261*
Y00889*
X06261*
Y00889*
X06262*
Y0089*
X06262*
Y0089*
X06263*
Y00891*
X06263*
Y00892*
X06264*
Y00892*
X06264*
Y00893*
X06265*
Y00893*
X06265*
Y00894*
X06266*
Y00894*
X06266*
Y00895*
X06267*
Y00895*
X06268*
Y00896*
X06268*
Y00896*
X06269*
Y00897*
X06269*
Y00897*
X0627*
Y00898*
X0627*
Y00899*
X06271*
Y00899*
X06272*
Y009*
X06272*
Y009*
X06273*
Y00901*
X06274*
Y00901*
X06274*
Y00902*
X06275*
Y00902*
X06275*
Y00903*
X06276*
Y00903*
X06276*
Y00904*
X06277*
Y00905*
X06277*
Y00905*
X06278*
Y00906*
X06278*
Y00906*
X06279*
Y00907*
X06279*
Y00907*
X0628*
Y00908*
X06281*
Y00908*
X06281*
Y00909*
X06282*
Y00909*
X06282*
Y0091*
X06283*
Y0091*
X06283*
Y00911*
X06284*
Y00912*
X06284*
Y00912*
X06285*
Y00913*
X06285*
Y00913*
X06286*
Y00914*
X06286*
Y00914*
X06287*
Y00915*
X06288*
Y00915*
Y00916*
X06288*
Y00916*
X06289*
Y00917*
Y00918*
X06289*
Y00918*
Y00919*
X0629*
Y00919*
Y0092*
X0629*
Y0092*
Y00921*
Y00921*
Y00922*
X06291*
Y00922*
Y00923*
Y00923*
Y00924*
Y00925*
Y00925*
Y00926*
Y00926*
Y00927*
Y00927*
Y00928*
Y00928*
Y00929*
Y00929*
Y0093*
Y0093*
Y00931*
Y00932*
Y00932*
Y00933*
Y00933*
Y00934*
Y00934*
Y00935*
Y00935*
Y00936*
Y00936*
Y00937*
Y00938*
Y00938*
Y00939*
Y00939*
Y0094*
Y0094*
Y00941*
Y00941*
Y00942*
Y00942*
Y00943*
Y00943*
Y00944*
Y00945*
Y00945*
Y00946*
Y00946*
Y00947*
Y00947*
Y00948*
Y00948*
Y00949*
Y00949*
Y0095*
Y0095*
Y00951*
Y00952*
Y00952*
Y00953*
Y00953*
Y00954*
Y00954*
Y00955*
Y00955*
Y00956*
Y00956*
Y00957*
Y00958*
Y00958*
Y00959*
Y00959*
Y0096*
Y0096*
Y00961*
Y00961*
Y00962*
Y00962*
Y00963*
Y00963*
Y00964*
Y00965*
Y00965*
Y00966*
Y00966*
Y00967*
Y00967*
Y00968*
Y00968*
Y00969*
Y00969*
Y0097*
Y0097*
Y00971*
Y00972*
Y00972*
Y00973*
Y00973*
Y00974*
Y00974*
Y00975*
Y00975*
Y00976*
Y00976*
Y00977*
Y00978*
Y00978*
Y00979*
Y00979*
Y0098*
Y0098*
Y00981*
Y00981*
Y00982*
Y00982*
Y00983*
Y00983*
Y00984*
Y00985*
Y00985*
Y00986*
Y00986*
Y00987*
Y00987*
Y00988*
Y00988*
Y00989*
Y00989*
Y0099*
Y0099*
Y00991*
Y00992*
Y00992*
Y00993*
Y00993*
Y00994*
Y00994*
Y00995*
Y00995*
Y00996*
Y00996*
Y00997*
Y00998*
Y00998*
Y00999*
Y00999*
Y01*
Y01*
Y01001*
Y01001*
Y01002*
Y01002*
Y01003*
Y01003*
Y01004*
Y01005*
Y01005*
Y01006*
Y01006*
Y01007*
Y01007*
Y01008*
Y01008*
Y01009*
Y01009*
Y0101*
Y0101*
Y01011*
Y01012*
Y01012*
Y01013*
Y01013*
Y01014*
Y01014*
Y01015*
Y01015*
Y01016*
Y01016*
Y01017*
Y01018*
Y01018*
Y01019*
Y01019*
Y0102*
Y0102*
Y01021*
Y01021*
Y01022*
Y01022*
Y01023*
Y01023*
Y01024*
Y01025*
Y01025*
Y01026*
Y01026*
Y01027*
Y01027*
Y01028*
Y01028*
Y01029*
Y01029*
Y0103*
Y0103*
Y01031*
Y01032*
Y01032*
Y01033*
Y01033*
Y01034*
Y01034*
Y01035*
Y01035*
Y01036*
Y01036*
Y01037*
Y01038*
Y01038*
Y01039*
Y01039*
Y0104*
Y0104*
Y01041*
Y01041*
Y01042*
Y01042*
Y01043*
Y01043*
Y01044*
Y01045*
Y01045*
Y01046*
Y01046*
Y01047*
Y01047*
Y01048*
Y01048*
Y01049*
Y01049*
Y0105*
Y0105*
Y01051*
Y01052*
Y01052*
Y01053*
Y01053*
Y01054*
Y01054*
Y01055*
Y01055*
Y01056*
Y01056*
Y01057*
Y01058*
Y01058*
Y01059*
Y01059*
Y0106*
Y0106*
Y01061*
Y01061*
Y01062*
Y01062*
Y01063*
Y01063*
Y01064*
Y01065*
Y01065*
Y01066*
Y01066*
Y01067*
Y01067*
Y01068*
Y01068*
Y01069*
Y01069*
Y0107*
Y0107*
Y01071*
Y01072*
Y01072*
Y01073*
Y01073*
Y01074*
Y01074*
Y01075*
Y01075*
Y01076*
Y01076*
Y01077*
Y01078*
Y01078*
Y01079*
Y01079*
Y0108*
Y0108*
Y01081*
Y01081*
Y01082*
Y01082*
Y01083*
Y01083*
Y01084*
Y01085*
Y01085*
Y01086*
Y01086*
Y01087*
Y01087*
Y01088*
Y01088*
Y01089*
Y01089*
Y0109*
X0629*
Y01091*
Y01091*
Y01092*
Y01092*
X0629*
Y01093*
Y01093*
X06289*
Y01094*
X06289*
Y01094*
X06288*
Y01095*
X06288*
Y01095*
X06287*
Y01096*
X06286*
Y01096*
X06286*
Y01097*
X06285*
Y01098*
X06285*
Y01098*
X06284*
Y01099*
X06284*
Y01099*
X06283*
Y011*
X06283*
Y011*
X06282*
Y01101*
X06282*
Y01101*
X06281*
Y01102*
X06281*
Y01102*
X0628*
Y01103*
X06279*
Y01103*
X06279*
Y01104*
X06278*
Y01105*
X06278*
Y01105*
X06277*
Y01106*
X06277*
Y01106*
X06276*
Y01107*
X06276*
Y01107*
X06275*
Y01108*
X06275*
Y01108*
X06274*
Y01109*
X06271*
Y01109*
G37*
G36*
X06533Y00918D02*
X06458D01*
Y00917*
X06457*
Y00916*
X06457*
Y00916*
X06456*
Y00915*
X06456*
Y00915*
Y00914*
Y00914*
Y00913*
Y00913*
Y00912*
Y00912*
Y00911*
Y0091*
Y0091*
Y00909*
Y00909*
Y00908*
Y00908*
Y00907*
Y00907*
Y00906*
Y00906*
Y00905*
Y00905*
Y00904*
Y00903*
Y00903*
Y00902*
Y00902*
Y00901*
Y00901*
Y009*
Y009*
Y00899*
Y00899*
Y00898*
Y00897*
Y00897*
Y00896*
Y00896*
Y00895*
Y00895*
Y00894*
Y00894*
Y00893*
Y00893*
Y00892*
Y00892*
Y00891*
Y0089*
Y0089*
Y00889*
Y00889*
Y00888*
Y00888*
Y00887*
Y00887*
Y00886*
Y00886*
Y00885*
Y00885*
Y00884*
Y00883*
Y00883*
Y00882*
Y00882*
Y00881*
Y00881*
Y0088*
Y0088*
Y00879*
Y00879*
Y00878*
Y00877*
Y00877*
Y00876*
Y00876*
Y00875*
Y00875*
Y00874*
Y00874*
Y00873*
Y00873*
Y00872*
Y00872*
Y00871*
Y0087*
Y0087*
Y00869*
Y00869*
Y00868*
Y00868*
Y00867*
Y00867*
Y00866*
Y00866*
Y00865*
Y00865*
Y00864*
Y00863*
Y00863*
Y00862*
Y00862*
Y00861*
Y00861*
Y0086*
Y0086*
Y00859*
Y00859*
Y00858*
Y00857*
Y00857*
Y00856*
Y00856*
Y00855*
Y00855*
Y00854*
Y00854*
Y00853*
Y00853*
Y00852*
Y00852*
Y00851*
Y0085*
Y0085*
Y00849*
Y00849*
Y00848*
Y00848*
Y00847*
Y00847*
Y00846*
Y00846*
Y00845*
Y00845*
Y00844*
Y00843*
Y00843*
Y00842*
Y00842*
Y00841*
Y00841*
Y0084*
Y0084*
Y00839*
Y00839*
Y00838*
Y00837*
Y00837*
Y00836*
Y00836*
Y00835*
Y00835*
Y00834*
Y00834*
Y00833*
Y00833*
Y00832*
Y00832*
Y00831*
Y0083*
Y0083*
Y00829*
Y00829*
Y00828*
Y00828*
Y00827*
Y00827*
Y00826*
Y00826*
Y00825*
Y00825*
Y00824*
Y00823*
Y00823*
Y00822*
Y00822*
Y00821*
Y00821*
Y0082*
Y0082*
Y00819*
Y00819*
Y00818*
Y00817*
Y00817*
Y00816*
Y00816*
Y00815*
Y00815*
Y00814*
Y00814*
Y00813*
Y00813*
Y00812*
Y00812*
Y00811*
Y0081*
Y0081*
Y00809*
Y00809*
Y00808*
Y00808*
Y00807*
Y00807*
Y00806*
Y00806*
Y00805*
Y00805*
Y00804*
Y00803*
Y00803*
Y00802*
Y00802*
Y00801*
X06456*
Y00801*
X06457*
Y008*
X06457*
Y008*
X06535*
Y008*
X06537*
Y00801*
X06538*
Y00801*
X06538*
Y00802*
X06539*
Y00802*
X06539*
Y00803*
X0654*
Y00803*
X06541*
Y00804*
X06541*
Y00805*
X06542*
Y00805*
X06542*
Y00806*
X06543*
Y00806*
X06543*
Y00807*
X06544*
Y00807*
X06544*
Y00808*
X06545*
Y00808*
X06545*
Y00809*
X06546*
Y00809*
X06547*
Y0081*
X06547*
Y0081*
X06548*
Y00811*
X06548*
Y00812*
X06549*
Y00812*
X06549*
Y00813*
X0655*
Y00813*
X0655*
Y00814*
X06551*
Y00814*
X06551*
Y00815*
X06552*
Y00815*
X06552*
Y00816*
X06553*
Y00816*
X06554*
Y00817*
Y00817*
Y00818*
X06554*
Y00819*
Y00819*
Y0082*
Y0082*
X06555*
Y00821*
Y00821*
Y00822*
Y00822*
Y00823*
Y00823*
Y00824*
Y00825*
Y00825*
Y00826*
Y00826*
Y00827*
Y00827*
Y00828*
Y00828*
Y00829*
Y00829*
Y0083*
Y0083*
Y00831*
Y00832*
Y00832*
Y00833*
Y00833*
Y00834*
Y00834*
Y00835*
Y00835*
Y00836*
Y00836*
Y00837*
Y00837*
Y00838*
Y00839*
Y00839*
Y0084*
Y0084*
Y00841*
Y00841*
Y00842*
Y00842*
Y00843*
Y00843*
Y00844*
Y00845*
Y00845*
Y00846*
Y00846*
Y00847*
Y00847*
Y00848*
Y00848*
Y00849*
Y00849*
Y0085*
Y0085*
Y00851*
Y00852*
Y00852*
Y00853*
Y00853*
Y00854*
Y00854*
Y00855*
Y00855*
Y00856*
Y00856*
Y00857*
Y00857*
Y00858*
Y00859*
Y00859*
Y0086*
Y0086*
Y00861*
Y00861*
Y00862*
Y00862*
Y00863*
Y00863*
Y00864*
Y00865*
Y00865*
Y00866*
Y00866*
Y00867*
Y00867*
Y00868*
Y00868*
Y00869*
Y00869*
Y0087*
Y0087*
Y00871*
Y00872*
Y00872*
Y00873*
Y00873*
Y00874*
Y00874*
Y00875*
Y00875*
Y00876*
Y00876*
Y00877*
Y00877*
Y00878*
Y00879*
Y00879*
Y0088*
Y0088*
Y00881*
Y00881*
Y00882*
Y00882*
Y00883*
Y00883*
Y00884*
Y00885*
Y00885*
Y00886*
Y00886*
Y00887*
Y00887*
Y00888*
Y00888*
Y00889*
Y00889*
Y0089*
Y0089*
Y00891*
Y00892*
Y00892*
Y00893*
Y00893*
Y00894*
Y00894*
Y00895*
Y00895*
Y00896*
Y00896*
Y00897*
X06554*
Y00897*
Y00898*
Y00899*
Y00899*
X06554*
Y009*
Y009*
X06553*
Y00901*
X06552*
Y00901*
X06552*
Y00902*
X06551*
Y00902*
X06551*
Y00903*
X0655*
Y00903*
X0655*
Y00904*
X06549*
Y00905*
X06549*
Y00905*
X06548*
Y00906*
X06548*
Y00906*
X06547*
Y00907*
X06547*
Y00907*
X06546*
Y00908*
X06545*
Y00908*
X06545*
Y00909*
X06544*
Y00909*
X06544*
Y0091*
X06543*
Y0091*
X06543*
Y00911*
X06542*
Y00912*
X06542*
Y00912*
X06541*
Y00913*
X06541*
Y00913*
X0654*
Y00914*
X06539*
Y00914*
X06539*
Y00915*
X06538*
Y00915*
X06538*
Y00916*
X06537*
Y00916*
X06536*
Y00917*
X06533*
Y00918*
G37*
G36*
X06418D02*
X06343D01*
Y00917*
X06342*
Y00916*
X06342*
Y00916*
X06341*
Y00915*
Y00915*
Y00914*
X06341*
Y00914*
Y00913*
Y00913*
Y00912*
Y00912*
Y00911*
Y0091*
Y0091*
Y00909*
Y00909*
Y00908*
Y00908*
Y00907*
Y00907*
Y00906*
Y00906*
Y00905*
Y00905*
Y00904*
Y00903*
Y00903*
Y00902*
Y00902*
Y00901*
Y00901*
Y009*
Y009*
Y00899*
Y00899*
Y00898*
Y00897*
Y00897*
Y00896*
Y00896*
Y00895*
Y00895*
Y00894*
Y00894*
Y00893*
Y00893*
Y00892*
Y00892*
Y00891*
Y0089*
Y0089*
Y00889*
Y00889*
Y00888*
Y00888*
Y00887*
Y00887*
Y00886*
Y00886*
Y00885*
Y00885*
Y00884*
Y00883*
Y00883*
Y00882*
Y00882*
Y00881*
Y00881*
Y0088*
Y0088*
Y00879*
Y00879*
Y00878*
Y00877*
Y00877*
Y00876*
Y00876*
Y00875*
Y00875*
Y00874*
Y00874*
Y00873*
Y00873*
Y00872*
Y00872*
Y00871*
Y0087*
Y0087*
Y00869*
Y00869*
Y00868*
Y00868*
Y00867*
Y00867*
Y00866*
Y00866*
Y00865*
Y00865*
Y00864*
Y00863*
Y00863*
Y00862*
Y00862*
Y00861*
Y00861*
Y0086*
Y0086*
Y00859*
Y00859*
Y00858*
Y00857*
Y00857*
Y00856*
Y00856*
Y00855*
Y00855*
Y00854*
Y00854*
Y00853*
Y00853*
Y00852*
Y00852*
Y00851*
Y0085*
Y0085*
Y00849*
Y00849*
Y00848*
Y00848*
Y00847*
Y00847*
Y00846*
Y00846*
Y00845*
Y00845*
Y00844*
Y00843*
Y00843*
Y00842*
Y00842*
Y00841*
Y00841*
Y0084*
Y0084*
Y00839*
Y00839*
Y00838*
Y00837*
Y00837*
Y00836*
Y00836*
Y00835*
Y00835*
Y00834*
Y00834*
Y00833*
Y00833*
Y00832*
Y00832*
Y00831*
Y0083*
Y0083*
Y00829*
Y00829*
Y00828*
Y00828*
Y00827*
Y00827*
Y00826*
Y00826*
Y00825*
Y00825*
Y00824*
Y00823*
Y00823*
Y00822*
Y00822*
Y00821*
Y00821*
Y0082*
Y0082*
Y00819*
Y00819*
Y00818*
Y00817*
Y00817*
Y00816*
Y00816*
Y00815*
Y00815*
Y00814*
Y00814*
Y00813*
Y00813*
Y00812*
Y00812*
Y00811*
Y0081*
Y0081*
Y00809*
Y00809*
Y00808*
Y00808*
Y00807*
Y00807*
Y00806*
Y00806*
Y00805*
Y00805*
Y00804*
Y00803*
X06341*
Y00803*
X06341*
Y00802*
X06341*
Y00802*
Y00801*
Y00801*
X06342*
Y008*
X06343*
Y008*
X06369*
Y008*
X0637*
Y00801*
X0637*
Y00801*
Y00802*
Y00802*
X06371*
Y00803*
Y00803*
Y00804*
Y00805*
Y00805*
Y00806*
Y00806*
Y00807*
Y00807*
Y00808*
Y00808*
Y00809*
Y00809*
Y0081*
Y0081*
Y00811*
Y00812*
Y00812*
Y00813*
Y00813*
Y00814*
Y00814*
Y00815*
Y00815*
Y00816*
Y00816*
Y00817*
Y00817*
Y00818*
Y00819*
Y00819*
Y0082*
Y0082*
Y00821*
Y00821*
Y00822*
Y00822*
Y00823*
Y00823*
Y00824*
Y00825*
Y00825*
Y00826*
Y00826*
Y00827*
Y00827*
Y00828*
Y00828*
Y00829*
Y00829*
Y0083*
Y0083*
Y00831*
Y00832*
X0637*
Y00832*
X06371*
Y00833*
Y00833*
Y00834*
Y00834*
Y00835*
X06391*
Y00834*
Y00834*
X06392*
Y00833*
Y00833*
X06392*
Y00832*
X06393*
Y00832*
Y00831*
X06394*
Y0083*
Y0083*
X06394*
Y00829*
X06395*
Y00829*
Y00828*
X06395*
Y00828*
Y00827*
X06396*
Y00827*
Y00826*
X06396*
Y00826*
X06397*
Y00825*
Y00825*
X06397*
Y00824*
Y00823*
X06398*
Y00823*
X06398*
Y00822*
Y00822*
X06399*
Y00821*
Y00821*
X06399*
Y0082*
X064*
Y0082*
Y00819*
X06401*
Y00819*
Y00818*
X06401*
Y00817*
Y00817*
X06402*
Y00816*
X06402*
Y00816*
Y00815*
X06403*
Y00815*
Y00814*
X06403*
Y00814*
X06404*
Y00813*
Y00813*
X06404*
Y00812*
Y00812*
X06405*
Y00811*
X06405*
Y0081*
Y0081*
X06406*
Y00809*
Y00809*
X06406*
Y00808*
X06407*
Y00808*
Y00807*
X06408*
Y00807*
Y00806*
X06408*
Y00806*
Y00805*
X06409*
Y00805*
X06409*
Y00804*
Y00803*
X0641*
Y00803*
Y00802*
X0641*
Y00802*
X06411*
Y00801*
X06411*
Y00801*
X06412*
Y008*
X06413*
Y008*
X06443*
Y008*
X06444*
Y00801*
Y00801*
Y00802*
Y00802*
X06443*
Y00803*
X06443*
Y00803*
Y00804*
X06442*
Y00805*
Y00805*
X06442*
Y00806*
X06441*
Y00806*
Y00807*
X06441*
Y00807*
Y00808*
X0644*
Y00808*
X06439*
Y00809*
Y00809*
X06439*
Y0081*
Y0081*
X06438*
Y00811*
X06438*
Y00812*
Y00812*
X06437*
Y00813*
Y00813*
X06437*
Y00814*
X06436*
Y00814*
Y00815*
X06436*
Y00815*
Y00816*
X06435*
Y00816*
X06435*
Y00817*
Y00817*
X06434*
Y00818*
Y00819*
X06434*
Y00819*
X06433*
Y0082*
Y0082*
X06432*
Y00821*
Y00821*
X06432*
Y00822*
X06431*
Y00822*
Y00823*
X06431*
Y00823*
Y00824*
X0643*
Y00825*
X0643*
Y00825*
Y00826*
X06429*
Y00826*
Y00827*
X06429*
Y00827*
X06428*
Y00828*
Y00828*
X06428*
Y00829*
Y00829*
X06427*
Y0083*
X06427*
Y0083*
Y00831*
X06426*
Y00832*
Y00832*
X06425*
Y00833*
Y00833*
X06425*
Y00834*
X06424*
Y00834*
Y00835*
X06424*
Y00835*
Y00836*
X06423*
Y00836*
X06423*
Y00837*
Y00837*
X06423*
Y00838*
X06424*
Y00839*
X06424*
Y00839*
X06425*
Y0084*
X06425*
Y0084*
X06426*
Y00841*
X06427*
Y00841*
X06427*
Y00842*
X06428*
Y00842*
X06428*
Y00843*
X06429*
Y00843*
X06429*
Y00844*
X0643*
Y00845*
X0643*
Y00845*
X06431*
Y00846*
X06431*
Y00846*
X06432*
Y00847*
X06432*
Y00847*
X06433*
Y00848*
X06434*
Y00848*
X06434*
Y00849*
X06435*
Y00849*
X06435*
Y0085*
Y0085*
X06436*
Y00851*
X06436*
Y00852*
X06437*
Y00852*
X06437*
Y00853*
X06438*
Y00853*
X06438*
Y00854*
Y00854*
X06439*
Y00855*
Y00855*
X06439*
Y00856*
Y00856*
Y00857*
Y00857*
Y00858*
Y00859*
Y00859*
Y0086*
Y0086*
Y00861*
Y00861*
Y00862*
Y00862*
Y00863*
Y00863*
Y00864*
Y00865*
Y00865*
Y00866*
Y00866*
Y00867*
Y00867*
Y00868*
Y00868*
Y00869*
Y00869*
Y0087*
Y0087*
Y00871*
Y00872*
Y00872*
Y00873*
Y00873*
Y00874*
Y00874*
Y00875*
Y00875*
Y00876*
Y00876*
Y00877*
Y00877*
Y00878*
Y00879*
Y00879*
Y0088*
Y0088*
Y00881*
Y00881*
Y00882*
Y00882*
Y00883*
Y00883*
Y00884*
Y00885*
Y00885*
Y00886*
Y00886*
Y00887*
Y00887*
Y00888*
Y00888*
Y00889*
Y00889*
Y0089*
Y0089*
Y00891*
Y00892*
Y00892*
Y00893*
Y00893*
Y00894*
Y00894*
Y00895*
Y00895*
Y00896*
Y00896*
Y00897*
Y00897*
Y00898*
X06439*
Y00899*
Y00899*
Y009*
X06438*
Y009*
Y00901*
X06438*
Y00901*
X06437*
Y00902*
X06437*
Y00902*
X06436*
Y00903*
X06436*
Y00903*
X06435*
Y00904*
X06435*
Y00905*
X06434*
Y00905*
X06434*
Y00906*
X06433*
Y00906*
X06432*
Y00907*
X06432*
Y00907*
X06431*
Y00908*
X06431*
Y00908*
X0643*
Y00909*
X0643*
Y00909*
X06429*
Y0091*
X06429*
Y0091*
X06428*
Y00911*
X06428*
Y00912*
X06427*
Y00912*
X06427*
Y00913*
X06426*
Y00913*
X06425*
Y00914*
X06425*
Y00914*
X06424*
Y00915*
X06424*
Y00915*
X06423*
Y00916*
X06422*
Y00916*
X06421*
Y00917*
X06418*
Y00918*
G37*
G36*
X06077Y00917D02*
X06071D01*
Y00916*
Y00916*
Y00915*
Y00915*
Y00914*
Y00914*
Y00913*
Y00913*
Y00912*
Y00912*
Y00911*
X06071*
Y0091*
Y0091*
Y00909*
Y00909*
Y00908*
Y00908*
Y00907*
Y00907*
Y00906*
Y00906*
Y00905*
X06072*
Y00905*
X06071*
Y00904*
X06072*
Y00903*
Y00903*
Y00902*
Y00902*
Y00901*
Y00901*
Y009*
Y009*
Y00899*
Y00899*
X06072*
Y00898*
Y00897*
Y00897*
Y00896*
Y00896*
Y00895*
Y00895*
Y00894*
X06073*
Y00894*
Y00893*
Y00893*
Y00892*
Y00892*
Y00891*
Y0089*
X06073*
Y0089*
Y00889*
Y00889*
Y00888*
Y00888*
Y00887*
X06074*
Y00887*
Y00886*
Y00886*
Y00885*
Y00885*
X06075*
Y00884*
Y00883*
Y00883*
Y00882*
Y00882*
X06075*
Y00881*
Y00881*
Y0088*
Y0088*
Y00879*
X06076*
Y00879*
Y00878*
Y00877*
Y00877*
Y00876*
X06076*
Y00876*
Y00875*
Y00875*
Y00874*
X06077*
Y00874*
Y00873*
Y00873*
Y00872*
X06077*
Y00872*
Y00871*
Y0087*
Y0087*
X06078*
Y00869*
Y00869*
Y00868*
Y00868*
X06078*
Y00867*
Y00867*
Y00866*
X06079*
Y00866*
Y00865*
Y00865*
Y00864*
X06079*
Y00863*
Y00863*
Y00862*
X0608*
Y00862*
Y00861*
Y00861*
X06081*
Y0086*
Y0086*
Y00859*
X06081*
Y00859*
Y00858*
Y00857*
X06082*
Y00857*
Y00856*
Y00856*
X06082*
Y00855*
Y00855*
Y00854*
X06083*
Y00854*
Y00853*
Y00853*
X06083*
Y00852*
Y00852*
Y00851*
X06084*
Y0085*
Y0085*
Y00849*
X06084*
Y00849*
Y00848*
X06085*
Y00848*
Y00847*
Y00847*
X06085*
Y00846*
Y00846*
X06086*
Y00845*
Y00845*
Y00844*
X06086*
Y00843*
Y00843*
X06087*
Y00842*
Y00842*
Y00841*
X06088*
Y00841*
Y0084*
X06088*
Y0084*
Y00839*
X06089*
Y00839*
Y00838*
Y00837*
X06089*
Y00837*
Y00836*
X0609*
Y00836*
Y00835*
X0609*
Y00835*
Y00834*
X06091*
Y00834*
Y00833*
X06091*
Y00833*
Y00832*
X06092*
Y00832*
Y00831*
X06092*
Y0083*
Y0083*
X06093*
Y00829*
Y00829*
X06093*
Y00828*
Y00828*
X06094*
Y00827*
Y00827*
X06095*
Y00826*
Y00826*
X06095*
Y00825*
Y00825*
X06096*
Y00824*
Y00823*
X06096*
Y00823*
X06097*
Y00822*
Y00822*
X06097*
Y00821*
Y00821*
X06098*
Y0082*
Y0082*
X06098*
Y00819*
Y00819*
X06099*
Y00818*
X06099*
Y00817*
Y00817*
X061*
Y00816*
Y00816*
X06101*
Y00815*
Y00815*
X06101*
Y00814*
X06102*
Y00814*
Y00813*
X06102*
Y00813*
X06103*
Y00812*
Y00812*
X06103*
Y00811*
Y0081*
X06104*
Y0081*
X06104*
Y00809*
Y00809*
X06105*
Y00808*
X06105*
Y00808*
Y00807*
X06106*
Y00807*
X06106*
Y00806*
Y00806*
X06107*
Y00805*
X06108*
Y00805*
Y00804*
X06108*
Y00803*
X06109*
Y00803*
X06109*
Y00802*
Y00802*
X0611*
Y00801*
X0611*
Y00801*
Y008*
X06111*
Y008*
X06111*
Y00799*
X06112*
Y00799*
Y00798*
X06112*
Y00797*
X06113*
Y00797*
X06113*
Y00796*
Y00796*
X06114*
Y00795*
X06115*
Y00795*
X06115*
Y00794*
X06116*
Y00794*
Y00793*
X06116*
Y00793*
X06117*
Y00792*
X06117*
Y00792*
X06118*
Y00791*
Y0079*
X06118*
Y0079*
X06119*
Y00789*
X06119*
Y00789*
X0612*
Y00788*
Y00788*
X06121*
Y00787*
X06121*
Y00787*
X06122*
Y00786*
X06122*
Y00786*
X06123*
Y00785*
X06123*
Y00785*
X06124*
Y00784*
Y00783*
X06124*
Y00783*
X06125*
Y00782*
X06125*
Y00782*
X06126*
Y00781*
X06126*
Y00781*
X06127*
Y0078*
X06128*
Y0078*
X06128*
Y00779*
X06129*
Y00779*
X06129*
Y00778*
X0613*
Y00777*
X0613*
Y00777*
X06131*
Y00776*
X06131*
Y00776*
X06132*
Y00775*
X06132*
Y00775*
X06133*
Y00774*
X06133*
Y00774*
X06134*
Y00773*
X06135*
Y00773*
X06135*
Y00772*
X06136*
Y00772*
X06136*
Y00771*
X06137*
Y0077*
X06137*
Y0077*
X06138*
Y00769*
X06138*
Y00769*
X06139*
Y00768*
X06139*
Y00768*
X0614*
Y00767*
X06141*
Y00767*
X06142*
Y00766*
X06142*
Y00766*
X06143*
Y00765*
X06143*
Y00765*
X06144*
Y00764*
X06144*
Y00763*
X06145*
Y00763*
X06146*
Y00762*
X06146*
Y00762*
X06147*
Y00761*
X06148*
Y00761*
X06149*
Y0076*
X06149*
Y0076*
X0615*
Y00759*
X0615*
Y00759*
X06151*
Y00758*
X06152*
Y00757*
X06152*
Y00757*
X06153*
Y00756*
X06154*
Y00756*
X06155*
Y00755*
X06156*
Y00755*
X06156*
Y00754*
X06157*
Y00754*
X06158*
Y00753*
X06158*
Y00753*
X06159*
Y00752*
X0616*
Y00752*
X06161*
Y00751*
X06162*
Y0075*
X06162*
Y0075*
X06163*
Y00749*
X06164*
Y00749*
X06165*
Y00748*
X06165*
Y00748*
X06166*
Y00747*
X06167*
Y00747*
X06168*
Y00746*
X06169*
Y00746*
X0617*
Y00745*
X06171*
Y00745*
X06171*
Y00744*
X06172*
Y00743*
X06173*
Y00743*
X06174*
Y00742*
X06175*
Y00742*
X06176*
Y00741*
X06177*
Y00741*
X06178*
Y0074*
X06179*
Y0074*
X0618*
Y00739*
X06181*
Y00739*
X06182*
Y00738*
X06183*
Y00737*
X06184*
Y00737*
X06185*
Y00736*
X06186*
Y00736*
X06188*
Y00735*
X06189*
Y00735*
X0619*
Y00734*
X06191*
Y00734*
X06192*
Y00733*
X06193*
Y00733*
X06194*
Y00732*
X06196*
Y00732*
X06197*
Y00731*
X06198*
Y0073*
X06199*
Y0073*
X06201*
Y00729*
X06202*
Y00729*
X06203*
Y00728*
X06205*
Y00728*
X06206*
Y00727*
X06208*
Y00727*
X06209*
Y00726*
X06211*
Y00726*
X06212*
Y00725*
X06213*
Y00725*
X06215*
Y00724*
X06217*
Y00723*
X06219*
Y00723*
X06221*
Y00722*
X06223*
Y00722*
X06224*
Y00721*
X06226*
Y00721*
X06229*
Y0072*
X06231*
Y0072*
X06233*
Y00719*
X06236*
Y00719*
X06238*
Y00718*
X06241*
Y00717*
X06244*
Y00717*
X06247*
Y00716*
X06251*
Y00716*
X06255*
Y00715*
X0626*
Y00715*
X06266*
Y00714*
X06292*
Y00715*
X06299*
Y00715*
X06304*
Y00716*
X06309*
Y00716*
X06312*
Y00717*
X06316*
Y00717*
X06318*
Y00718*
X06322*
Y00719*
X06324*
Y00719*
X06326*
Y0072*
X06329*
Y0072*
X06331*
Y00721*
X06333*
Y00721*
X06335*
Y00722*
X06337*
Y00722*
X06339*
Y00723*
X06341*
Y00723*
X06342*
Y00724*
X06344*
Y00725*
X06345*
Y00725*
X06347*
Y00726*
X06349*
Y00726*
X0635*
Y00727*
X06352*
Y00727*
X06354*
Y00728*
X06355*
Y00728*
X06356*
Y00729*
X06357*
Y00729*
X06359*
Y0073*
X0636*
Y0073*
X06362*
Y00731*
X06363*
Y00732*
X06364*
Y00732*
X06365*
Y00733*
X06366*
Y00733*
X06368*
Y00734*
X06369*
Y00734*
X0637*
Y00735*
X06371*
Y00735*
X06372*
Y00736*
X06373*
Y00736*
X06374*
Y00737*
X06375*
Y00737*
X06376*
Y00738*
X06377*
Y00739*
X06378*
Y00739*
X06379*
Y0074*
X06381*
Y0074*
X06381*
Y00741*
X06382*
Y00741*
X06383*
Y00742*
X06384*
Y00742*
X06385*
Y00743*
X06386*
Y00743*
X06387*
Y00744*
X06388*
Y00745*
X06389*
Y00745*
X0639*
Y00746*
X0639*
Y00746*
X06391*
Y00747*
X06392*
Y00747*
X06393*
Y00748*
X06394*
Y00748*
X06395*
Y00749*
X06396*
Y00749*
X06396*
Y0075*
X06397*
Y0075*
X06398*
Y00751*
X06398*
Y00752*
X06399*
Y00752*
X064*
Y00753*
X06401*
Y00753*
X06402*
Y00754*
X06403*
Y00754*
X06403*
Y00755*
X06404*
Y00755*
X06405*
Y00756*
X06405*
Y00756*
X06406*
Y00757*
X06407*
Y00757*
X06408*
Y00758*
X06408*
Y00759*
X06409*
Y00759*
X0641*
Y0076*
X0641*
Y0076*
X06411*
Y00761*
X06411*
Y00761*
X06412*
Y00762*
X06413*
Y00762*
X06414*
Y00763*
X06414*
Y00763*
X06415*
Y00764*
X06416*
Y00765*
X06416*
Y00765*
X06417*
Y00766*
X06417*
Y00766*
X06418*
Y00767*
X06418*
Y00767*
X06419*
Y00768*
X0642*
Y00768*
X06421*
Y00769*
X06421*
Y00769*
X06422*
Y0077*
X06422*
Y0077*
X06423*
Y00771*
X06423*
Y00772*
X06424*
Y00772*
X06424*
Y00773*
X06425*
Y00773*
X06425*
Y00774*
X06426*
Y00774*
X06427*
Y00775*
X06427*
Y00775*
X06428*
Y00776*
X06428*
Y00776*
X06429*
Y00777*
X06429*
Y00777*
X0643*
Y00778*
X0643*
Y00779*
X06431*
Y00779*
X06431*
Y0078*
X06432*
Y0078*
X06432*
Y00781*
X06433*
Y00781*
X06434*
Y00782*
X06434*
Y00782*
X06435*
Y00783*
X06435*
Y00783*
Y00784*
X06436*
Y00785*
X06436*
Y00785*
X06437*
Y00786*
X06437*
Y00786*
X06438*
Y00787*
X06438*
Y00787*
X06439*
Y00788*
Y00788*
X06439*
Y00789*
X06431*
Y00788*
X0643*
Y00788*
X0643*
Y00787*
Y00787*
X06429*
Y00786*
X06429*
Y00786*
X06428*
Y00785*
X06428*
Y00785*
X06427*
Y00784*
X06427*
Y00783*
X06426*
Y00783*
X06425*
Y00782*
X06425*
Y00782*
X06424*
Y00781*
X06424*
Y00781*
X06423*
Y0078*
X06423*
Y0078*
X06422*
Y00779*
X06422*
Y00779*
X06421*
Y00778*
X06421*
Y00777*
X0642*
Y00777*
X06419*
Y00776*
X06419*
Y00776*
X06418*
Y00775*
X06418*
Y00775*
X06417*
Y00774*
X06417*
Y00774*
X06416*
Y00773*
X06415*
Y00773*
X06415*
Y00772*
X06414*
Y00772*
X06414*
Y00771*
X06413*
Y0077*
X06412*
Y0077*
X06412*
Y00769*
X06411*
Y00769*
X0641*
Y00768*
X0641*
Y00768*
X06409*
Y00767*
X06409*
Y00767*
X06408*
Y00766*
X06407*
Y00766*
X06406*
Y00765*
X06406*
Y00765*
X06405*
Y00764*
X06404*
Y00763*
X06404*
Y00763*
X06403*
Y00762*
X06402*
Y00762*
X06402*
Y00761*
X06401*
Y00761*
X064*
Y0076*
X06399*
Y0076*
X06399*
Y00759*
X06398*
Y00759*
X06397*
Y00758*
X06396*
Y00757*
X06396*
Y00757*
X06395*
Y00756*
X06394*
Y00756*
X06394*
Y00755*
X06392*
Y00755*
X06392*
Y00754*
X06391*
Y00754*
X0639*
Y00753*
X06389*
Y00753*
X06389*
Y00752*
X06388*
Y00752*
X06386*
Y00751*
X06386*
Y0075*
X06385*
Y0075*
X06384*
Y00749*
X06383*
Y00749*
X06382*
Y00748*
X06381*
Y00748*
X06381*
Y00747*
X06379*
Y00747*
X06378*
Y00746*
X06377*
Y00746*
X06377*
Y00745*
X06376*
Y00745*
X06375*
Y00744*
X06374*
Y00743*
X06372*
Y00743*
X06371*
Y00742*
X0637*
Y00742*
X06369*
Y00741*
X06368*
Y00741*
X06367*
Y0074*
X06366*
Y0074*
X06365*
Y00739*
X06364*
Y00739*
X06363*
Y00738*
X06361*
Y00737*
X0636*
Y00737*
X06358*
Y00736*
X06357*
Y00736*
X06356*
Y00735*
X06355*
Y00735*
X06354*
Y00734*
X06352*
Y00734*
X0635*
Y00733*
X06349*
Y00733*
X06348*
Y00732*
X06346*
Y00732*
X06344*
Y00731*
X06343*
Y0073*
X06341*
Y0073*
X06339*
Y00729*
X06338*
Y00729*
X06336*
Y00728*
X06334*
Y00728*
X06332*
Y00727*
X0633*
Y00727*
X06328*
Y00726*
X06325*
Y00726*
X06323*
Y00725*
X06321*
Y00725*
X06318*
Y00724*
X06315*
Y00723*
X06311*
Y00723*
X06308*
Y00722*
X06304*
Y00722*
X06298*
Y00721*
X06292*
Y00721*
X06291*
Y00721*
X0629*
Y00721*
X06269*
Y00721*
X06261*
Y00722*
X06256*
Y00722*
X06252*
Y00723*
X06248*
Y00723*
X06245*
Y00724*
X06242*
Y00725*
X06239*
Y00725*
X06236*
Y00726*
X06234*
Y00726*
X06232*
Y00727*
X0623*
Y00727*
X06228*
Y00728*
X06225*
Y00728*
X06224*
Y00729*
X06222*
Y00729*
X0622*
Y0073*
X06218*
Y0073*
X06217*
Y00731*
X06215*
Y00732*
X06213*
Y00732*
X06212*
Y00733*
X0621*
Y00733*
X06209*
Y00734*
X06208*
Y00734*
X06206*
Y00735*
X06205*
Y00735*
X06203*
Y00736*
X06202*
Y00736*
X06201*
Y00737*
X06199*
Y00737*
X06198*
Y00738*
X06197*
Y00739*
X06196*
Y00739*
X06195*
Y0074*
X06193*
Y0074*
X06192*
Y00741*
X06191*
Y00741*
X0619*
Y00742*
X06189*
Y00742*
X06188*
Y00743*
X06187*
Y00743*
X06186*
Y00744*
X06185*
Y00745*
X06184*
Y00745*
X06183*
Y00746*
X06182*
Y00746*
X06181*
Y00747*
X0618*
Y00747*
X06179*
Y00748*
X06178*
Y00748*
X06177*
Y00749*
X06176*
Y00749*
X06175*
Y0075*
X06175*
Y0075*
X06173*
Y00751*
X06173*
Y00752*
X06172*
Y00752*
X06171*
Y00753*
X0617*
Y00753*
X06169*
Y00754*
X06169*
Y00754*
X06168*
Y00755*
X06167*
Y00755*
X06166*
Y00756*
X06165*
Y00756*
X06164*
Y00757*
X06164*
Y00757*
X06163*
Y00758*
X06162*
Y00759*
X06162*
Y00759*
X06161*
Y0076*
X0616*
Y0076*
X06159*
Y00761*
X06158*
Y00761*
X06158*
Y00762*
X06157*
Y00762*
X06156*
Y00763*
X06156*
Y00763*
X06155*
Y00764*
X06154*
Y00765*
X06153*
Y00765*
X06153*
Y00766*
X06152*
Y00766*
X06151*
Y00767*
X06151*
Y00767*
X0615*
Y00768*
X0615*
Y00768*
X06149*
Y00769*
X06148*
Y00769*
X06148*
Y0077*
X06147*
Y0077*
X06146*
Y00771*
X06146*
Y00772*
X06145*
Y00772*
X06145*
Y00773*
X06144*
Y00773*
X06143*
Y00774*
X06143*
Y00774*
X06142*
Y00775*
X06142*
Y00775*
X06141*
Y00776*
X06141*
Y00776*
X0614*
Y00777*
X06139*
Y00777*
X06139*
Y00778*
X06138*
Y00779*
X06138*
Y00779*
X06137*
Y0078*
X06137*
Y0078*
X06136*
Y00781*
X06136*
Y00781*
X06135*
Y00782*
X06135*
Y00782*
X06134*
Y00783*
X06133*
Y00783*
X06133*
Y00784*
X06132*
Y00785*
X06132*
Y00785*
X06131*
Y00786*
X06131*
Y00786*
X0613*
Y00787*
X0613*
Y00787*
X06129*
Y00788*
Y00788*
X06129*
Y00789*
X06128*
Y00789*
X06128*
Y0079*
X06127*
Y0079*
X06126*
Y00791*
X06126*
Y00792*
X06125*
Y00792*
Y00793*
X06125*
Y00793*
X06124*
Y00794*
X06124*
Y00794*
X06123*
Y00795*
X06123*
Y00795*
Y00796*
X06122*
Y00796*
X06122*
Y00797*
X06121*
Y00797*
X06121*
Y00798*
Y00799*
X0612*
Y00799*
X06119*
Y008*
X06119*
Y008*
Y00801*
X06118*
Y00801*
X06118*
Y00802*
X06117*
Y00802*
Y00803*
X06117*
Y00803*
X06116*
Y00804*
X06116*
Y00805*
Y00805*
X06115*
Y00806*
X06115*
Y00806*
X06114*
Y00807*
Y00807*
X06113*
Y00808*
X06113*
Y00808*
Y00809*
X06112*
Y00809*
X06112*
Y0081*
Y0081*
X06111*
Y00811*
X06111*
Y00812*
Y00812*
X0611*
Y00813*
X0611*
Y00813*
Y00814*
X06109*
Y00814*
X06109*
Y00815*
Y00815*
X06108*
Y00816*
Y00816*
X06108*
Y00817*
X06107*
Y00817*
Y00818*
X06106*
Y00819*
X06106*
Y00819*
Y0082*
X06105*
Y0082*
Y00821*
X06105*
Y00821*
Y00822*
X06104*
Y00822*
X06104*
Y00823*
Y00823*
X06103*
Y00824*
Y00825*
X06103*
Y00825*
Y00826*
X06102*
Y00826*
X06102*
Y00827*
Y00827*
X06101*
Y00828*
Y00828*
X06101*
Y00829*
Y00829*
X061*
Y0083*
Y0083*
X06099*
Y00831*
Y00832*
X06099*
Y00832*
Y00833*
X06098*
Y00833*
Y00834*
X06098*
Y00834*
Y00835*
X06097*
Y00835*
Y00836*
X06097*
Y00836*
Y00837*
X06096*
Y00837*
Y00838*
X06096*
Y00839*
Y00839*
X06095*
Y0084*
Y0084*
Y00841*
X06095*
Y00841*
Y00842*
X06094*
Y00842*
Y00843*
X06093*
Y00843*
Y00844*
Y00845*
X06093*
Y00845*
Y00846*
X06092*
Y00846*
Y00847*
X06092*
Y00847*
Y00848*
Y00848*
X06091*
Y00849*
Y00849*
X06091*
Y0085*
Y0085*
Y00851*
X0609*
Y00852*
Y00852*
Y00853*
X0609*
Y00853*
Y00854*
X06089*
Y00854*
Y00855*
Y00855*
X06089*
Y00856*
Y00856*
Y00857*
X06088*
Y00857*
Y00858*
Y00859*
X06088*
Y00859*
Y0086*
Y0086*
X06087*
Y00861*
Y00861*
Y00862*
X06086*
Y00862*
Y00863*
Y00863*
X06086*
Y00864*
Y00865*
Y00865*
X06085*
Y00866*
Y00866*
Y00867*
Y00867*
X06085*
Y00868*
Y00868*
Y00869*
X06084*
Y00869*
Y0087*
Y0087*
Y00871*
X06084*
Y00872*
Y00872*
Y00873*
Y00873*
X06083*
Y00874*
Y00874*
Y00875*
Y00875*
X06083*
Y00876*
Y00876*
Y00877*
Y00877*
X06082*
Y00878*
Y00879*
Y00879*
Y0088*
Y0088*
X06082*
Y00881*
Y00881*
Y00882*
Y00882*
Y00883*
X06081*
Y00883*
Y00884*
Y00885*
Y00885*
Y00886*
X06081*
Y00886*
Y00887*
Y00887*
Y00888*
Y00888*
X0608*
Y00889*
Y00889*
Y0089*
Y0089*
Y00891*
Y00892*
X06079*
Y00892*
Y00893*
Y00893*
Y00894*
Y00894*
Y00895*
Y00895*
X06079*
Y00896*
Y00896*
Y00897*
Y00897*
Y00898*
Y00899*
Y00899*
Y009*
X06078*
Y009*
Y00901*
Y00901*
Y00902*
Y00902*
Y00903*
Y00903*
Y00904*
Y00905*
Y00905*
X06078*
Y00906*
Y00906*
Y00907*
Y00907*
Y00908*
Y00908*
Y00909*
Y00909*
Y0091*
Y0091*
Y00911*
Y00912*
Y00912*
Y00913*
Y00913*
Y00914*
X06077*
Y00914*
Y00915*
Y00915*
Y00916*
Y00916*
Y00917*
G37*
%LNtimingcard_pcb-3*%
%LPD*%
G36*
X06524Y00888D02*
X06525D01*
Y00888*
Y00887*
Y00887*
Y00886*
Y00886*
Y00885*
Y00885*
Y00884*
Y00883*
Y00883*
Y00882*
Y00882*
Y00881*
Y00881*
Y0088*
Y0088*
Y00879*
Y00879*
Y00878*
Y00877*
Y00877*
Y00876*
Y00876*
Y00875*
Y00875*
Y00874*
Y00874*
Y00873*
Y00873*
Y00872*
Y00872*
Y00871*
Y0087*
Y0087*
Y00869*
Y00869*
Y00868*
Y00868*
Y00867*
Y00867*
Y00866*
Y00866*
Y00865*
Y00865*
Y00864*
Y00863*
Y00863*
Y00862*
Y00862*
Y00861*
Y00861*
Y0086*
Y0086*
Y00859*
Y00859*
Y00858*
Y00857*
Y00857*
Y00856*
Y00856*
Y00855*
Y00855*
Y00854*
Y00854*
Y00853*
Y00853*
Y00852*
Y00852*
Y00851*
Y0085*
Y0085*
Y00849*
Y00849*
Y00848*
Y00848*
Y00847*
Y00847*
Y00846*
Y00846*
Y00845*
Y00845*
Y00844*
Y00843*
Y00843*
Y00842*
Y00842*
Y00841*
Y00841*
Y0084*
Y0084*
Y00839*
Y00839*
Y00838*
Y00837*
Y00837*
Y00836*
Y00836*
Y00835*
Y00835*
Y00834*
Y00834*
Y00833*
Y00833*
Y00832*
Y00832*
Y00831*
Y0083*
Y0083*
Y00829*
Y00829*
Y00828*
X06485*
Y00829*
Y00829*
Y0083*
Y0083*
Y00831*
Y00832*
Y00832*
Y00833*
Y00833*
Y00834*
Y00834*
Y00835*
Y00835*
Y00836*
Y00836*
Y00837*
Y00837*
Y00838*
Y00839*
Y00839*
Y0084*
Y0084*
Y00841*
Y00841*
Y00842*
Y00842*
Y00843*
Y00843*
Y00844*
Y00845*
Y00845*
Y00846*
Y00846*
Y00847*
Y00847*
Y00848*
Y00848*
Y00849*
Y00849*
Y0085*
Y0085*
Y00851*
Y00852*
Y00852*
Y00853*
Y00853*
Y00854*
Y00854*
Y00855*
Y00855*
Y00856*
Y00856*
Y00857*
Y00857*
Y00858*
Y00859*
Y00859*
Y0086*
Y0086*
Y00861*
Y00861*
Y00862*
Y00862*
Y00863*
Y00863*
Y00864*
Y00865*
Y00865*
Y00866*
Y00866*
Y00867*
Y00867*
Y00868*
Y00868*
Y00869*
Y00869*
Y0087*
Y0087*
Y00871*
Y00872*
Y00872*
Y00873*
Y00873*
Y00874*
Y00874*
Y00875*
Y00875*
Y00876*
Y00876*
Y00877*
Y00877*
Y00878*
Y00879*
Y00879*
Y0088*
Y0088*
Y00881*
Y00881*
Y00882*
Y00882*
Y00883*
Y00883*
Y00884*
Y00885*
Y00885*
Y00886*
Y00886*
Y00887*
Y00887*
Y00888*
Y00888*
X06486*
Y00889*
X06487*
Y00888*
X06522*
Y00889*
X06522*
Y00888*
X06523*
Y00889*
X06524*
Y00888*
G37*
G36*
X0641Y00889D02*
Y00889D01*
Y00888*
Y00888*
Y00887*
Y00887*
Y00886*
Y00886*
Y00885*
Y00885*
Y00884*
Y00883*
Y00883*
Y00882*
Y00882*
Y00881*
Y00881*
Y0088*
Y0088*
Y00879*
Y00879*
Y00878*
Y00877*
Y00877*
Y00876*
Y00876*
Y00875*
Y00875*
Y00874*
Y00874*
Y00873*
Y00873*
Y00872*
Y00872*
Y00871*
Y0087*
Y0087*
Y00869*
Y00869*
Y00868*
Y00868*
Y00867*
Y00867*
Y00866*
Y00866*
Y00865*
Y00865*
Y00864*
Y00863*
Y00863*
Y00862*
Y00862*
Y00861*
X06369*
Y00862*
Y00862*
Y00863*
Y00863*
Y00864*
Y00865*
Y00865*
Y00866*
Y00866*
Y00867*
Y00867*
Y00868*
Y00868*
Y00869*
Y00869*
Y0087*
Y0087*
Y00871*
Y00872*
Y00872*
Y00873*
Y00873*
Y00874*
Y00874*
Y00875*
Y00875*
Y00876*
Y00876*
Y00877*
Y00877*
Y00878*
Y00879*
Y00879*
Y0088*
Y0088*
Y00881*
Y00881*
Y00882*
Y00882*
Y00883*
Y00883*
Y00884*
Y00885*
Y00885*
Y00886*
Y00886*
Y00887*
Y00887*
Y00888*
Y00888*
Y00889*
Y00889*
Y0089*
X0641*
Y00889*
G37*
G54D14*
X02606Y01062D02*
Y011D01*
X0261Y01104D02*
Y01106D01*
X02606Y011D02*
X0261Y01104D01*
X03438Y02892D02*
X03438Y02892D01*
X03414Y02892D02*
X03438D01*
X03676Y01712D02*
X03718D01*
X03718Y01713*
X0359Y01634D02*
X03609Y01614D01*
X0359Y01634D02*
Y01662D01*
X0333Y03301D02*
Y03392D01*
X03333Y03395*
X01721Y01685D02*
X01723D01*
X0173Y01692*
X0175*
X01669Y01685D02*
X0167D01*
X01662Y01692D02*
X01669Y01685D01*
X01642Y01692D02*
X01662D01*
X03693Y03117D02*
X03704Y03107D01*
Y03085D02*
Y03107D01*
Y03085D02*
X03717Y03072D01*
X03877Y03078D02*
Y03079D01*
X02209Y03716D02*
X02215D01*
X02233Y03734D02*
Y03735D01*
X02239Y03741D02*
X02258D01*
X02215Y03716D02*
X02233Y03734D01*
Y03735D02*
X02239Y03741D01*
X03601Y02087D02*
X03651D01*
X03586Y02047D02*
X03651D01*
X03581Y02067D02*
X03651D01*
X03599Y02028D02*
X03651D01*
X02139Y03624D02*
Y03653D01*
Y03664*
X06367Y02462D02*
X0645D01*
X06365Y0246D02*
X06367Y02462D01*
X06359Y02535D02*
X0645D01*
X06359Y02606D02*
X06452D01*
X06359Y02673D02*
X06451D01*
X06359Y0274D02*
X0645D01*
X06627Y01529D02*
X06629Y01531D01*
X06587Y01529D02*
X06627D01*
X06594Y01775D02*
X06642D01*
X06642Y0172D02*
X06642Y01721D01*
X06594Y0172D02*
X06642D01*
X01873Y04276D02*
Y04281D01*
Y04244D02*
Y04276D01*
X01721Y01989D02*
X01721Y01988D01*
X03492Y02067D02*
X03562D01*
X03596Y01514D02*
X03598Y01516D01*
X03406Y01461D02*
Y01462D01*
X02881Y02566D02*
X02882Y02565D01*
X03492Y02047D02*
X03556D01*
X02882Y02518D02*
Y02565D01*
X03409Y01465D02*
Y01468D01*
X02685Y02311D02*
X02685Y02311D01*
X03651Y01418D02*
X03732D01*
X03448Y01506D02*
Y01507D01*
X02606Y00878D02*
Y00931D01*
X0341Y01713D02*
X03463D01*
X03571Y02058D02*
X03581Y02067D01*
X01714Y01595D02*
X01715Y01595D01*
X01776*
X03598Y01516D02*
X03651D01*
X01617Y01988D02*
X01674D01*
X01674Y01989*
X01717Y01398D02*
X01776D01*
X03581Y02067D02*
X03601Y02087D01*
X03491Y01713D02*
X03492Y01713D01*
X01617Y01496D02*
X01645D01*
X01719Y01496D02*
X01776D01*
X02606Y00931D02*
X02608Y00934D01*
X01617Y01792D02*
X01671D01*
X03463Y01713D02*
X03491D01*
X03457Y01516D02*
X03492D01*
X03463Y01713D02*
X03463Y01713D01*
X03448Y01507D02*
X03457Y01516D01*
X01721Y0189D02*
X01722Y0189D01*
X03594Y01514D02*
X03596D01*
X03421Y01811D02*
X03492D01*
X03594Y02033D02*
X03599Y02028D01*
X03414Y01805D02*
X03421Y01811D01*
X03554Y02033D02*
X03571D01*
X01617Y0189D02*
X01675D01*
X03413Y01593D02*
X03435Y01614D01*
X01722Y0189D02*
X01776D01*
X01617Y01792D02*
X01617Y01792D01*
X03406Y01462D02*
X03409Y01465D01*
X01645Y01496D02*
X01645Y01497D01*
X03435Y01614D02*
X03492D01*
X01617Y01595D02*
X0167D01*
X0167Y01595*
X03562Y02067D02*
X03571Y02058D01*
X03609Y01614D02*
X03651D01*
X03556Y02047D02*
X03571Y02033D01*
X01721Y01988D02*
X01776D01*
X01617Y01398D02*
X01671D01*
X0355Y02028D02*
X03554Y02033D01*
X03571D02*
X03594D01*
X01718Y01792D02*
X01718Y01792D01*
X01716Y01399D02*
X01717Y01398D01*
X01675Y0189D02*
X01675Y01891D01*
X02685Y02311D02*
Y02358D01*
X01617Y01496D02*
X01617Y01496D01*
X03413Y01573D02*
Y01593D01*
X01645Y01497D02*
X01671D01*
X01671Y01398D02*
X01671Y01399D01*
X01718Y01792D02*
X01776D01*
X03548Y01413D02*
X03549D01*
X01718Y01497D02*
X01719Y01496D01*
X03543Y01418D02*
X03548Y01413D01*
X03492Y01418D02*
X03543D01*
X03542Y02087D02*
X03562Y02067D01*
X03492Y02028D02*
X0355D01*
X03571Y02033D02*
X03586Y02047D01*
X03492Y02087D02*
X03542D01*
X03409Y01468D02*
X03448Y01506D01*
X03987Y03783D02*
X04039D01*
X04039Y03784*
X01726Y04329D02*
X01727Y04328D01*
Y04273D02*
Y04328D01*
X01788Y04289D02*
Y04329D01*
X01933Y04257D02*
D01*
X01873Y04281D02*
X0189Y04299D01*
X01933Y04129D02*
Y04257D01*
X04476Y03129D02*
Y03133D01*
X04477Y03135*
X04454Y03108D02*
X04476Y03129D01*
X04064Y02722D02*
Y0278D01*
X06628Y01372D02*
X06629Y01372D01*
Y01421*
X03911Y01639D02*
X03911Y01639D01*
X03957Y01659D02*
X03968Y01671D01*
X04033Y01547D02*
X04034Y01546D01*
X03925Y01599D02*
X03951D01*
X03925Y01599D02*
X03925Y01599D01*
X03911Y01599D02*
X03925D01*
X03969Y01552D02*
Y01581D01*
X03911Y01619D02*
X03911Y01619D01*
X03964D02*
X03994Y01589D01*
X0413Y01686D02*
X04131D01*
X04068Y01679D02*
X04123D01*
X04033Y01547D02*
Y01575D01*
X03996Y01711D02*
X04025Y01739D01*
X03994Y01551D02*
Y01589D01*
X04025Y01739D02*
X04068D01*
X03911Y01619D02*
X03964D01*
X03911Y01639D02*
X03969D01*
X04033Y01575*
X04123Y01679D02*
X0413Y01686D01*
X03911Y01659D02*
X03957D01*
X03951Y01599D02*
X03969Y01581D01*
X03959Y02725D02*
X0396Y02724D01*
X03959Y02725D02*
Y0278D01*
X03625Y00726D02*
X03659D01*
X03603Y00704D02*
X03625Y00726D01*
X03603Y00682D02*
Y00704D01*
X06439Y03026D02*
Y03071D01*
Y03026D02*
X06456Y03009D01*
X01908Y04129D02*
X01933D01*
X01878Y04099D02*
X01908Y04129D01*
X01846Y04099D02*
X01878D01*
X01914Y04276D02*
X01933Y04257D01*
X01879Y04276D02*
X01914D01*
X01853Y04225D02*
X01873Y04244D01*
X01687Y04225D02*
X01853D01*
X01664Y04248D02*
X01687Y04225D01*
X01664Y04248D02*
Y04273D01*
X03477Y02797D02*
X03484Y02804D01*
Y02892*
X01788Y04289D02*
X01802Y04276D01*
X03772Y03758D02*
X03825D01*
X03829Y03762*
X0383*
X03344Y04221D02*
X03394D01*
X03395Y04222*
X04272Y03079D02*
X04274Y03077D01*
X04272Y03079D02*
Y03135D01*
X04209Y03135D02*
Y03246D01*
X04208Y03135D02*
X04209Y03135D01*
X04209Y03129D02*
X04219Y0312D01*
X04209Y03129D02*
Y03133D01*
X04208Y03135D02*
X04209Y03133D01*
X04219Y03077D02*
Y0312D01*
X04164Y03077D02*
Y03117D01*
X04153Y03127D02*
X04164Y03117D01*
X04153Y03127D02*
Y03133D01*
X04152Y03135D02*
X04153Y03133D01*
X01157Y01956D02*
Y01956D01*
X012Y02*
X01248*
X04039Y03092D02*
X04052Y03105D01*
Y03119*
X04068Y03135*
X01631Y04099D02*
X01671D01*
X01691Y04079*
X06477Y03231D02*
X06511D01*
X06476Y03231D02*
X06477Y03231D01*
X04334Y03077D02*
Y03134D01*
X04333Y03135D02*
X04334Y03134D01*
X04454Y03077D02*
Y03108D01*
X01601Y04273D02*
X01664D01*
X01557Y04229D02*
X01601Y04273D01*
X01157Y02481D02*
X0126D01*
X01261Y02482*
X04109Y03077D02*
Y03126D01*
X04113Y03129*
Y03133*
X04114Y03135*
X06604Y03327D02*
X06618Y03341D01*
X06648*
X02888Y04221D02*
X02944D01*
X02888Y04221D02*
X02888Y04221D01*
X01764Y04124D02*
X01846D01*
X01749Y0411D02*
X01764Y04124D01*
X02281Y0417D02*
Y04207D01*
X0229Y04217*
X03688Y03329D02*
X03701Y03342D01*
X03744*
X05733Y03361D02*
Y03556D01*
X05676Y03362D02*
Y03545D01*
X05676Y03546*
X03659Y00723D02*
Y00726D01*
X06736Y01818D02*
Y01821D01*
X06727Y0183D02*
X06736Y01821D01*
X06694Y0183D02*
X06727D01*
X06637Y01881D02*
X06699D01*
X06906Y02096D02*
X06948D01*
X06949Y02095*
X0665Y02176D02*
X06659Y02166D01*
X06607Y02176D02*
X0665D01*
X06334Y0211D02*
X06395D01*
X06395Y02111*
X06048Y02171D02*
X06093D01*
X06003Y02389D02*
Y0243D01*
X06274Y02391D02*
X06352D01*
X04954Y04203D02*
X04957Y04206D01*
X0491Y04203D02*
X04954D01*
X04387Y04206D02*
X04432D01*
X03778Y04023D02*
X03779Y04023D01*
X03777Y04023D02*
X03778D01*
X03779Y04023D02*
X03808D01*
X04104Y03841D02*
X04104Y03841D01*
X04104Y03841D02*
Y03873D01*
X04085Y03892D02*
X04104Y03873D01*
X04194Y03837D02*
Y03884D01*
X04394Y03077D02*
Y03078D01*
X04402Y03086*
X04403*
X04431Y03114*
Y03135*
X0286Y0375D02*
Y03784D01*
X0286Y03785*
X02745Y03742D02*
Y0375D01*
X0274Y03737D02*
X02745Y03742D01*
X02732Y03737D02*
X0274D01*
X02724Y03729D02*
X02732Y03737D01*
X02724Y03729D02*
Y03729D01*
X03495Y03697D02*
X03531Y03661D01*
Y0366D02*
Y03661D01*
X03495Y03697D02*
Y0375D01*
X0327D02*
Y03784D01*
X03269Y03785D02*
X0327Y03784D01*
X01157Y01431D02*
X01198Y01472D01*
X01242*
X01157Y00906D02*
X01193Y00942D01*
X01256*
G54D17*
X03407Y01411D02*
X03431D01*
X03444Y01398*
X03492*
G54D19*
X02862Y00795D02*
D01*
X02862Y00795*
X02862Y00795*
X02862Y00795*
X02862Y00795*
X02862Y00795*
X02862Y00795*
X02862Y00795*
X02862Y00795*
X02862Y00796*
X02862Y00796*
X02862Y00796*
X02862Y00796*
X027Y0083D02*
D01*
X02701Y00831*
X02702Y00832*
X02702Y00833*
X02703Y00833*
X02703Y00834*
X02704Y00835*
X02704Y00836*
X02704Y00837*
X02704Y00838*
X02705Y00839*
X02705Y0084*
X02705Y00841*
X027Y0083D02*
D01*
X02699Y00829*
X02698Y00827*
X02697Y00826*
X02696Y00824*
X02695Y00823*
X02694Y00821*
X02694Y00819*
X02693Y00817*
X02693Y00815*
X02693Y00814*
X02692Y00812*
X02692Y00811*
X02681Y00976D02*
D01*
X02681Y00976*
X02681Y00976*
X02681Y00976*
X02682Y00976*
X02682Y00976*
X02682Y00976*
X02683Y00976*
X02683Y00977*
X02683Y00977*
X02683Y00977*
X02684Y00977*
X02684Y00977*
X02684Y00978*
X02684Y00978*
X02684Y00978*
X02684Y00978*
X02685Y00979*
X02685Y00979*
X02685Y00979*
X02685Y00979*
X02685Y0098*
X02685Y0098*
X02685Y0098*
X02799Y00976D02*
D01*
X02799Y00976*
X02799Y00976*
X028Y00976*
X028Y00976*
X028Y00976*
X028Y00976*
X02801Y00976*
X02801Y00977*
X02801Y00977*
X02801Y00977*
X02802Y00977*
X02802Y00977*
X02802Y00978*
X02802Y00978*
X02802Y00978*
X02803Y00978*
X02803Y00979*
X02803Y00979*
X02803Y00979*
X02803Y00979*
X02803Y0098*
X02803Y0098*
X02803Y0098*
X02606Y00815D02*
D01*
X02605Y00813*
X02604Y00812*
X02603Y0081*
X02602Y00809*
X02601Y00807*
X026Y00805*
X02599Y00803*
X02599Y00801*
X02598Y00799*
X02598Y00797*
X02598Y00795*
X02598Y00795*
X0274Y00976D02*
D01*
X0274Y00976*
X0274Y00976*
X02741Y00976*
X02741Y00976*
X02741Y00976*
X02741Y00976*
X02742Y00976*
X02742Y00977*
X02742Y00977*
X02742Y00977*
X02743Y00977*
X02743Y00977*
X02743Y00978*
X02743Y00978*
X02743Y00978*
X02744Y00978*
X02744Y00979*
X02744Y00979*
X02744Y00979*
X02744Y00979*
X02744Y0098*
X02744Y0098*
X02744Y0098*
X02629Y00818D02*
D01*
X02632Y00821*
X02634Y00824*
X02637Y00827*
X02639Y00831*
X0264Y00834*
X02642Y00838*
X02643Y00841*
X02644Y00845*
X02645Y00849*
X02645Y00853*
X02646Y00856*
X02646Y00857*
X02759Y00795D02*
D01*
X0276Y00796*
X02761Y00796*
X02761Y00797*
X02762Y00798*
X02762Y00799*
X02763Y008*
X02763Y00801*
X02763Y00802*
X02763Y00803*
X02764Y00804*
X02764Y00805*
X02764Y00805*
X02679Y00828D02*
D01*
X02679Y00828*
X02679Y00828*
X02679Y00828*
X02679Y00828*
X02679Y00828*
D01*
X02677Y00826*
X02674Y00823*
X02673Y00821*
X02671Y00818*
X02669Y00815*
X02668Y00812*
X02667Y00809*
X02666Y00805*
X02665Y00802*
X02665Y00799*
X02665Y00796*
X02665Y00795*
X02823Y00803D02*
D01*
X02823Y00802*
X02823Y00802*
X02823Y00801*
X02823Y008*
X02823Y00799*
X02824Y00798*
X02824Y00798*
X02825Y00797*
X02825Y00796*
X02826Y00796*
X02826Y00795*
X02826Y00795*
X02799D02*
D01*
X02799Y00796*
X028Y00796*
X02801Y00797*
X02801Y00798*
X02802Y00799*
X02802Y008*
X02802Y00801*
X02803Y00802*
X02803Y00803*
X02803Y00804*
X02803Y00805*
X02803Y00805*
X02705Y00979D02*
D01*
X02705Y00979*
X02705Y00979*
X02705Y00979*
X02705Y00978*
X02705Y00978*
X02705Y00978*
X02705Y00978*
X02705Y00978*
X02705Y00977*
X02705Y00977*
X02706Y00977*
X02706Y00977*
X02706Y00977*
X02706Y00976*
X02706Y00976*
X02707Y00976*
X02707Y00976*
X02707Y00976*
X02707Y00976*
X02708Y00976*
X02708Y00976*
X02708Y00976*
X02708Y00976*
X02618Y00826D02*
D01*
X02619Y00828*
X0262Y00829*
X02621Y00831*
X02622Y00833*
X02623Y00834*
X02624Y00836*
X02625Y00838*
X02625Y0084*
X02626Y00842*
X02626Y00844*
X02626Y00846*
X02626Y00846*
X02681Y0083D02*
D01*
X02681Y00831*
X02682Y00832*
X02683Y00833*
X02683Y00833*
X02684Y00834*
X02684Y00835*
X02684Y00836*
X02685Y00837*
X02685Y00838*
X02685Y00839*
X02685Y0084*
X02685Y00841*
X02823Y00979D02*
D01*
X02823Y00979*
X02823Y00979*
X02823Y00979*
X02823Y00978*
X02823Y00978*
X02823Y00978*
X02823Y00978*
X02823Y00978*
X02823Y00977*
X02824Y00977*
X02824Y00977*
X02824Y00977*
X02824Y00977*
X02824Y00976*
X02824Y00976*
X02825Y00976*
X02825Y00976*
X02825Y00976*
X02825Y00976*
X02826Y00976*
X02826Y00976*
X02826Y00976*
X02826Y00976*
X02646Y00979D02*
D01*
X02646Y00979*
X02646Y00979*
X02646Y00979*
X02646Y00978*
X02646Y00978*
X02646Y00978*
X02646Y00978*
X02646Y00978*
X02646Y00977*
X02646Y00977*
X02647Y00977*
X02647Y00977*
X02647Y00977*
X02647Y00976*
X02647Y00976*
X02648Y00976*
X02648Y00976*
X02648Y00976*
X02648Y00976*
X02648Y00976*
X02649Y00976*
X02649Y00976*
X02649Y00976*
X02622D02*
D01*
X02622Y00976*
X02622Y00976*
X02622Y00976*
X02623Y00976*
X02623Y00976*
X02623Y00976*
X02624Y00976*
X02624Y00977*
X02624Y00977*
X02624Y00977*
X02625Y00977*
X02625Y00977*
X02625Y00978*
X02625Y00978*
X02625Y00978*
X02625Y00978*
X02626Y00979*
X02626Y00979*
X02626Y00979*
X02626Y00979*
X02626Y0098*
X02626Y0098*
X02626Y0098*
X02764Y00979D02*
D01*
X02764Y00979*
X02764Y00979*
X02764Y00979*
X02764Y00978*
X02764Y00978*
X02764Y00978*
X02764Y00978*
X02764Y00978*
X02764Y00977*
X02764Y00977*
X02765Y00977*
X02765Y00977*
X02765Y00977*
X02765Y00976*
X02765Y00976*
X02766Y00976*
X02766Y00976*
X02766Y00976*
X02766Y00976*
X02767Y00976*
X02767Y00976*
X02767Y00976*
X02767Y00976*
X02629Y00818D02*
D01*
X02629Y00818*
X02628Y00817*
X02628Y00816*
X02627Y00815*
X02627Y00815*
X02626Y00814*
X02626Y00813*
X02626Y00812*
X02626Y00811*
X02626Y0081*
X02625Y00809*
X02625Y00809*
X0274Y00819D02*
D01*
X0274Y00819*
X02741Y0082*
X02742Y00821*
X02742Y00822*
X02743Y00823*
X02743Y00824*
X02743Y00824*
X02744Y00825*
X02744Y00826*
X02744Y00827*
X02744Y00828*
X02744Y00829*
X0274Y00819D02*
D01*
X02738Y00817*
X02737Y00816*
X02736Y00814*
X02735Y00812*
X02734Y00811*
X02734Y00809*
X02733Y00807*
X02732Y00805*
X02732Y00803*
X02732Y00802*
X02732Y008*
X02732Y00799*
X02882Y00822D02*
D01*
X02882Y0082*
X02882Y00817*
X02883Y00814*
X02883Y00812*
X02884Y00809*
X02885Y00806*
X02886Y00804*
X02888Y00802*
X02889Y00799*
X02891Y00797*
X02893Y00795*
X02893Y00795*
X02584Y00265D02*
D01*
X02584Y00266*
X02584Y00268*
X02584Y00269*
X02583Y0027*
X02583Y00272*
X02582Y00273*
X02582Y00274*
X02581Y00275*
X0258Y00277*
X02579Y00278*
X02578Y00279*
X02578Y00279*
X02905D02*
D01*
X02905Y00279*
X02905Y00279*
X02905Y00279*
X02905Y00279*
X02905Y00279*
Y00279*
D01*
X02904Y00278*
X02903Y00277*
X02902Y00276*
X02902Y00275*
X02901Y00273*
X029Y00272*
X029Y00271*
X029Y00269*
X02899Y00268*
X02899Y00266*
X02899Y00265*
X02899Y00265*
X02746Y00278D02*
D01*
X02745Y00277*
X02745Y00275*
X02744Y00274*
X02743Y00273*
X02743Y00272*
X02742Y0027*
X02742Y00269*
X02742Y00268*
X02742Y00266*
X02742Y00265*
X02742Y00265*
X02746Y00278D02*
D01*
X02747Y00278*
X02747Y00278*
X02747Y00279*
X02747Y00279*
X02747Y00279*
X02748Y00282D02*
D01*
X02748Y00281*
X02748Y00281*
X02748Y00281*
X0261Y00259D02*
D01*
X0261Y00257*
X0261Y00255*
X0261Y00253*
X02611Y00251*
X02611Y00249*
X02612Y00248*
X02613Y00246*
X02614Y00244*
X02615Y00243*
X02616Y00241*
X02617Y0024*
X02618Y0024*
X02624Y00225D02*
D01*
X02623Y00227*
X02623Y00228*
X02623Y0023*
X02623Y00231*
X02622Y00232*
X02622Y00234*
X02621Y00235*
X0262Y00236*
X0262Y00237*
X02619Y00238*
X02618Y00239*
X02618Y0024*
X02781Y00274D02*
D01*
X02781Y00275*
X02781Y00275*
X02781Y00276*
X02781Y00276*
X02781Y00277*
X0278Y00277*
X0278Y00277*
X0278Y00278*
X0278Y00278*
X02779Y00279*
X02779Y00279*
X02779Y00279*
X02938Y00274D02*
D01*
X02938Y00275*
X02938Y00275*
X02938Y00276*
X02938Y00276*
X02938Y00277*
X02938Y00277*
X02938Y00277*
X02937Y00278*
X02937Y00278*
X02937Y00279*
X02937Y00279*
X02937Y00279*
X02413D02*
D01*
X02409Y00275*
X02405Y0027*
X02401Y00265*
X02398Y0026*
X02395Y00254*
X02393Y00249*
X02391Y00243*
X0239Y00237*
X02388Y00231*
X02388Y00225*
X02387Y00219*
X02387Y00217*
X02444Y00279D02*
D01*
X02442Y00276*
X02439Y00273*
X02436Y00269*
X02434Y00266*
X02432Y00262*
X02431Y00258*
X02429Y00254*
X02428Y0025*
X02427Y00246*
X02427Y00242*
X02427Y00237*
X02427Y00236*
X02781Y00112D02*
D01*
X02781Y00112*
X02781Y00111*
X02781Y00111*
X02781Y00111*
X02781Y00111*
X02781Y00111*
X02782Y00111*
X02782Y00111*
X02782Y00111*
X02782Y00111*
X02782Y00111*
X02782Y00111*
X02772Y00133D02*
D01*
X02772Y00131*
X02773Y00129*
X02773Y00127*
X02774Y00124*
X02774Y00122*
X02775Y0012*
X02776Y00118*
X02777Y00116*
X02778Y00114*
X0278Y00113*
X02781Y00111*
X02782Y00111*
X02612Y00139D02*
D01*
X02612Y00137*
X02613Y00134*
X02613Y00131*
X02614Y00128*
X02615Y00125*
X02616Y00123*
X02617Y0012*
X02619Y00118*
X0262Y00115*
X02622Y00113*
X02624Y00111*
X02624Y00111*
X02575Y00134D02*
D01*
X02575Y00131*
X02576Y00129*
X02576Y00127*
X02577Y00125*
X02577Y00123*
X02578Y0012*
X02579Y00118*
X0258Y00116*
X02582Y00114*
X02583Y00113*
X02585Y00111*
X02585Y00111*
X02418Y00133D02*
D01*
X02418Y0013*
X02419Y00128*
X02419Y00126*
X0242Y00124*
X0242Y00122*
X02421Y0012*
X02422Y00118*
X02423Y00116*
X02424Y00114*
X02426Y00113*
X02427Y00111*
X02427Y00111*
X02705Y00841D02*
Y00878D01*
X02764Y00979D02*
Y01038D01*
X02862Y00796D02*
Y00878D01*
X02803Y01038D02*
X02803Y01038D01*
X02744Y0098D02*
Y01038D01*
X02685Y0098D02*
Y01038D01*
X02732Y00799D02*
Y00799D01*
X02685Y00841D02*
Y00878D01*
X02646Y00857D02*
Y00878D01*
X02626Y00846D02*
Y00878D01*
X02823Y00803D02*
Y00878D01*
X02803Y00805D02*
Y00878D01*
X02679Y00828D02*
Y00828D01*
X02646Y00979D02*
Y01038D01*
X02882Y00822D02*
Y00878D01*
X02803Y0098D02*
Y01038D01*
X02692Y00795D02*
Y00811D01*
X02625Y00795D02*
Y00809D01*
X02732Y00795D02*
Y00799D01*
X02626Y0098D02*
Y01038D01*
X02679Y00828D02*
X02681Y0083D01*
X02606Y00815D02*
X02618Y00826D01*
X02705Y00979D02*
Y01038D01*
X02764Y00805D02*
Y00878D01*
X02744Y00829D02*
Y00878D01*
X02823Y00979D02*
Y01038D01*
X0261Y00259D02*
Y00279D01*
X02905Y00279D02*
X02905Y00279D01*
X02899Y00137D02*
Y00265D01*
X02746Y00278D02*
X02746Y00278D01*
X02747Y00279D02*
X02748Y00281D01*
X02748Y00282D02*
X02748Y00282D01*
X02748Y00282*
X02781Y00137D02*
Y00274D01*
X02742Y00137D02*
Y00265D01*
X02584Y00137D02*
Y00265D01*
X02899Y00137D02*
D01*
X02624D02*
Y00225D01*
X02938Y00137D02*
Y00274D01*
X02387Y00137D02*
Y00217D01*
X02427Y00137D02*
Y00236D01*
X02742Y00111D02*
X02745Y00113D01*
X0274Y00113D02*
X02742Y00111D01*
X02931Y00118D02*
X02939Y00111D01*
X029D02*
X02907Y00118D01*
G54D22*
X02948Y02432D02*
D01*
X02948Y02432*
Y02432*
Y02432*
X02948Y02432*
X02948Y02432*
X03441Y01892D02*
D01*
X03442Y01892*
X03442Y01892*
X03443Y01891*
X03443Y01891*
X03444Y01891*
X03444Y01891*
X03445Y0189*
X03445Y0189*
X03446Y0189*
X03446Y0189*
X03447Y0189*
X03447Y0189*
X03365Y01968D02*
D01*
X03365Y01969*
X03365Y01969*
X03364Y01969*
X03364Y0197*
X03363Y0197*
X03363Y0197*
X03362Y0197*
X03362Y0197*
X03361Y0197*
X0336Y01971*
X0336Y01971*
X0336Y01971*
X02684Y02716D02*
D01*
X02685Y02716*
X02685Y02716*
X02686Y02716*
X02686Y02716*
X02687Y02717*
X02687Y02717*
X02688Y02717*
X02688Y02717*
X02689Y02718*
X02689Y02718*
X0269Y02718*
X0269Y02718*
X02449D02*
D01*
X02449Y02718*
X0245Y02718*
X0245Y02717*
X02451Y02717*
X02451Y02717*
X02452Y02717*
X02452Y02716*
X02453Y02716*
X02453Y02716*
X02454Y02716*
X02454Y02716*
X02455Y02716*
X02928Y00161D02*
D01*
X02929Y00159*
X02929Y00157*
X02929Y00154*
X0293Y00152*
X02931Y0015*
X02931Y00148*
X02932Y00145*
X02934Y00143*
X02935Y00141*
X02936Y00139*
X02938Y00138*
X02938Y00137*
X02611Y023D02*
X02616D01*
X02587Y02324D02*
Y02356D01*
X02616Y023D02*
X02618Y02299D01*
X02586Y02357D02*
X02587Y02356D01*
Y02324D02*
X02611Y023D01*
X02671Y02291D02*
Y02293D01*
X02665Y02298D02*
X02671Y02293D01*
X02645Y0227D02*
Y02299D01*
X02665Y02298D02*
Y02358D01*
X02201Y03708D02*
X02209Y03716D01*
X02139Y03708D02*
X02201D01*
X06978Y0183D02*
X07Y01851D01*
Y01878*
X03602Y00641D02*
X03618D01*
X03622Y00645D02*
X03665D01*
X03618Y00641D02*
X03622Y00645D01*
X02311Y00877D02*
Y00926D01*
X02314Y0093*
Y00933*
X02409Y00926D02*
X02413Y0093D01*
Y00933*
X02409Y00877D02*
Y00926D01*
X02507Y00923D02*
X02515Y0093D01*
Y00933*
X02507Y00877D02*
Y00923D01*
X02901Y00877D02*
Y0093D01*
X02905Y00934D02*
Y00937D01*
X02901Y0093D02*
X02905Y00934D01*
X02901Y01037D02*
Y01106D01*
X02842Y01096D02*
X0285Y01104D01*
Y01106*
X02842Y01037D02*
Y01096D01*
X02783Y01037D02*
Y011D01*
X02787Y01104*
Y01106*
X02724Y01037D02*
Y011D01*
X02728Y01104*
Y01106*
X02665Y01037D02*
Y01106D01*
D01*
X02507Y01037D02*
Y01099D01*
X02511Y01103*
Y01105*
X02409Y01037D02*
Y01037D01*
Y01106*
X02311Y01037D02*
Y01106D01*
X02291Y02357D02*
Y02397D01*
X02322Y02429*
X02389Y02397D02*
X02421Y02429D01*
X02389Y02357D02*
Y02397D01*
X02488Y02357D02*
Y02423D01*
X02484Y02426D02*
Y02429D01*
Y02426D02*
X02488Y02423D01*
X02783Y02357D02*
X02783Y02357D01*
Y02433*
X02881Y023D02*
Y02357D01*
X02874Y02292D02*
X02881Y023D01*
X02874Y0229D02*
Y02292D01*
X02783Y02517D02*
Y02594D01*
X02779Y02598D02*
Y02601D01*
Y02598D02*
X02783Y02594D01*
X02685Y02517D02*
Y02594D01*
X02688Y02598D02*
Y02601D01*
X02685Y02594D02*
X02688Y02598D01*
X02586Y02594D02*
X0259Y02598D01*
Y02601*
X02586Y02517D02*
Y02594D01*
X02468Y02518D02*
Y02588D01*
X02488Y02517D02*
X02488Y02517D01*
Y02574*
Y02574*
X02468Y02518D02*
X02468Y02518D01*
X02468Y02588D02*
X02494Y02614D01*
Y02661*
X02385Y02611D02*
X02389Y02607D01*
X02385Y02611D02*
Y02613D01*
X02389Y02517D02*
Y02607D01*
X02279Y02612D02*
X02291Y026D01*
Y02517D02*
Y026D01*
X02279Y02612D02*
Y02614D01*
X02527Y02264D02*
Y02357D01*
Y02264D02*
X02527Y02264D01*
X03125Y02732D02*
D01*
X03051D02*
X03125D01*
X03358Y02736D02*
D01*
X03414*
X03299D02*
X03358D01*
X03269Y02766D02*
X03299Y02736D01*
X03269Y02766D02*
Y02795D01*
X04385Y03661D02*
Y03663D01*
X04375Y03673D02*
X04385Y03663D01*
X04375Y03673D02*
Y03776D01*
X04393Y0393D02*
Y03976D01*
Y0393D02*
X04394Y03929D01*
X03728Y03507D02*
X04318D01*
X03633Y03413D02*
X03728Y03507D01*
X04141Y03594D02*
Y03596D01*
X0414Y03597D02*
X04141Y03596D01*
X04116Y03597D02*
X0414D01*
X04141Y03594D02*
X0415Y03603D01*
X03633Y03401D02*
Y03413D01*
X03637Y03007D02*
Y03397D01*
X03633Y03401D02*
X03637Y03397D01*
Y03007D02*
X03834Y02811D01*
X03712Y01673D02*
X03834Y01795D01*
Y02811*
X03651Y01673D02*
X03712D01*
X03651Y01673D02*
X03651Y01673D01*
X03712D02*
X03712Y01673D01*
X03651Y01654D02*
X03699D01*
X03712Y01641*
X03749*
X04523Y03736D02*
Y03791D01*
X04677Y03603D02*
Y03759D01*
X04523Y03846D02*
X0459D01*
X04677Y03759*
X0307Y03393D02*
X0307Y03393D01*
X0284Y03187D02*
X03046Y03393D01*
X0307*
X03239Y03448D02*
X03358D01*
X03358Y03448*
X03377Y03467*
X03134Y03344D02*
X03239Y03448D01*
X03403Y03467D02*
X03414Y03455D01*
X03377Y03467D02*
X03403D01*
X03414Y03455D02*
Y03455D01*
X03435Y0341D02*
Y03434D01*
X03414Y03455D02*
X03435Y03434D01*
Y0341D02*
X03451Y03395D01*
X03566Y03486D02*
X03622D01*
X03518Y03437D02*
X03566Y03486D01*
X0445Y03675D02*
Y03776D01*
X04437Y03661D02*
Y03662D01*
X0445Y03675*
X04053Y03641D02*
Y03682D01*
X03987Y03708D02*
X04027D01*
X04053Y03682*
X04452Y03862D02*
X04476D01*
X0445Y0386D02*
X04452Y03862D01*
X04492Y03846D02*
X04523D01*
X04476Y03862D02*
X04492Y03846D01*
X04385Y0392D02*
X04394Y03929D01*
X04385Y03901D02*
Y0392D01*
X04375Y03891D02*
X04385Y03901D01*
X04375Y0386D02*
Y03891D01*
X0444Y03905D02*
Y03928D01*
X04439Y03929D02*
X0444Y03928D01*
X0445Y0386D02*
Y03895D01*
X0444Y03905D02*
X0445Y03895D01*
X03354Y02795D02*
Y02822D01*
Y02795D02*
X03358Y02791D01*
X03269Y02834D02*
X03342D01*
X03354Y02822*
X03157Y02787D02*
X03169Y02775D01*
X03125Y02787D02*
X03157D01*
X03169Y02759D02*
Y02775D01*
Y02759D02*
X03185Y02744D01*
X0322*
X03229Y02752*
Y02784*
Y0288D02*
X03344Y02996D01*
X03345Y02995*
X03444*
X03371Y0305D02*
X03372Y03051D01*
X03438*
X03368Y0305D02*
X03371D01*
X009Y01924D02*
X00929Y01952D01*
X00932Y01956*
X00713Y01952D02*
X00929D01*
X00199Y00906D02*
X00932D01*
X00199Y01431D02*
X00932D01*
X0071Y01956D02*
X00713Y01952D01*
X00199Y01956D02*
X0071D01*
X00966Y01216D02*
X00996D01*
X00966D02*
D01*
X01003Y01177D02*
Y01208D01*
X00996Y01216D02*
X01003Y01208D01*
X01014Y01705D02*
X01015D01*
X01815Y01614D02*
X01873Y01672D01*
X01878D02*
X01892Y01685D01*
X01873Y01672D02*
X01878D01*
X01892Y01685D02*
X01893D01*
X01Y01719D02*
X01014Y01705D01*
X00983Y01719D02*
X01D01*
X00959Y01743D02*
X00983Y01719D01*
X04547Y02896D02*
X04729Y02714D01*
X04547Y02896D02*
Y03074D01*
Y03148*
X0522Y04086D02*
Y04151D01*
X05218Y04153D02*
X0522Y04151D01*
X04692Y04149D02*
X04744D01*
X04754Y04138*
Y04115D02*
Y04138D01*
X06307Y03196D02*
X06311Y03201D01*
X06287Y03195D02*
X06289Y03196D01*
X06275Y0323D02*
X06286D01*
X06262Y0322D02*
X06265D01*
X06335Y03147D02*
X06337Y03148D01*
X06359Y03152D02*
X06388D01*
X06265Y0322D02*
X06275Y0323D01*
X06289Y03196D02*
X06307D01*
X06311Y03201D02*
X06331D01*
X06337Y03148D02*
X06355D01*
X06359Y03152*
X06286Y0323D02*
X06302Y03246D01*
X06586Y03003D02*
X06649D01*
X06003Y02335D02*
X06004Y02334D01*
X06064*
X06066Y02385D02*
X0609D01*
X06064Y02387D02*
X06066Y02385D01*
X0609D02*
X06098Y02377D01*
Y0235D02*
Y02377D01*
Y0235D02*
X06107Y02341D01*
X06157*
X06931Y01931D02*
X06939Y01922D01*
Y01932D02*
X06999D01*
X07Y01932*
X06937Y01881D02*
X06939Y01879D01*
X06909Y01881D02*
X06937D01*
X06897Y01893D02*
X06909Y01881D01*
X06897Y01893D02*
Y01921D01*
X06887Y01931D02*
X06897Y01921D01*
X06832Y01931D02*
X06887D01*
X06594Y0161D02*
X06631D01*
X06632Y01611*
X06594Y01673D02*
X0663D01*
X06632Y01671*
X06804Y01881D02*
X06832D01*
X02948Y02456D02*
X02948Y02432D01*
Y02428D02*
Y02432D01*
X0298Y02518D02*
Y02599D01*
X03537Y02008D02*
X03554Y01991D01*
X02961Y02311D02*
X02985Y02287D01*
X01568Y02067D02*
X01617D01*
X03439Y0187D02*
X03491D01*
X03197Y01715D02*
X03234Y01752D01*
X02567Y02358D02*
Y02403D01*
X02449Y02285D02*
X0245Y02284D01*
X03224Y01661D02*
X03244Y01681D01*
X03365Y01968D02*
X03372Y01962D01*
X0235Y02676D02*
X02394Y0272D01*
X02958Y02621D02*
X0298Y02599D01*
X03715Y01772D02*
X03719Y01767D01*
X02409Y02314D02*
X02409Y02314D01*
X02449Y02285D02*
Y02358D01*
X03696Y01634D02*
X03705Y01625D01*
X0235Y02518D02*
Y02676D01*
X01776Y01811D02*
X01879D01*
X02823Y02518D02*
Y02599D01*
X03719Y01766D02*
Y01767D01*
X03651Y0191D02*
X03708D01*
X0292Y02428D02*
X0292Y02428D01*
X03554Y01841D02*
X03584Y01811D01*
X03773Y01665D02*
Y01666D01*
X02331Y02215D02*
Y02358D01*
X03776Y01555D02*
X03795Y01536D01*
X02894Y02465D02*
X02901Y02472D01*
X03244Y01681D02*
X03271D01*
X01617Y02087D02*
Y02118D01*
X03584Y01811D02*
X03651D01*
X02901Y02472D02*
Y02518D01*
X03404Y01363D02*
X03409D01*
X02894Y02431D02*
Y02465D01*
X03652Y01478D02*
X03831D01*
X03491Y0187D02*
X03492Y0187D01*
X0292Y02428D02*
Y02517D01*
X02921Y02518*
X02567Y02403D02*
X02575Y02412D01*
X03271Y01681D02*
X03278Y01673D01*
X03547Y01438D02*
X03549Y01441D01*
X03705Y01625D02*
X0377D01*
X01776Y01674D02*
X01822D01*
X03651Y01634D02*
X03696D01*
X03651Y01555D02*
X03776D01*
X0298Y02358D02*
Y02396D01*
X01879Y01811D02*
X01882Y01809D01*
X03651Y01792D02*
X0376D01*
X03492Y01438D02*
X03547D01*
X0377Y01625D02*
X03804Y01659D01*
X03708Y0191D02*
X03719Y01921D01*
X02862Y02319D02*
Y02358D01*
X01754Y02088D02*
X01755Y02087D01*
X02821Y02601D02*
X02823Y02599D01*
X02599Y02431D02*
Y02436D01*
X03651Y0189D02*
X03651Y0189D01*
X03405Y01826D02*
X03411Y01831D01*
X01719Y01536D02*
X01776D01*
X03555Y0189D02*
X03651D01*
X03775Y01511D02*
X03864D01*
X03749Y01641D02*
X03773Y01665D01*
X03795Y01536D02*
X03924D01*
X03372Y01962D02*
X03441Y01892D01*
X02606Y02358D02*
Y02424D01*
X01567Y0131D02*
X01577Y01319D01*
X01776Y01516D02*
X01897D01*
X03447Y0189D02*
X03492D01*
X02901Y02304D02*
X0292Y02286D01*
X02702Y02295D02*
X02705Y02298D01*
X01776Y02067D02*
X01881D01*
X03379Y01386D02*
X03381Y01387D01*
X02624Y02461D02*
X02625Y02461D01*
X02449Y02518D02*
Y02597D01*
X03329Y01826D02*
X03405D01*
X03492Y02008D02*
X03537D01*
X03651Y01575D02*
X03779D01*
X03298Y01971D02*
X0336D01*
X02705Y0232D02*
X02705Y02319D01*
X03409Y01363D02*
X03413Y01359D01*
X02475Y02291D02*
Y02292D01*
X02429Y02358D02*
X02429Y02358D01*
X02463Y02612D02*
Y02674D01*
X03413Y01359D02*
X03492D01*
X02484Y02694D02*
X02493D01*
X0292Y02286D02*
X02942D01*
X03197Y01714D02*
Y01715D01*
X03651Y01496D02*
X03761D01*
X03431Y01378D02*
X03492D01*
X02724Y02297D02*
Y02358D01*
X01776Y01319D02*
X01797D01*
X01577D02*
X01617D01*
X03252Y01661D02*
X03265D01*
X02429Y02322D02*
X02429Y02322D01*
X03383Y01339D02*
X03492D01*
X02429Y02303D02*
Y02322D01*
X02948Y02428D02*
X0298Y02396D01*
X03761Y01496D02*
X03775Y01511D01*
X02547Y02313D02*
Y02358D01*
X01567Y01285D02*
Y0131D01*
X02599Y02431D02*
X02606Y02424D01*
X01617Y02118D02*
X01619Y02121D01*
X03651Y02008D02*
X03707D01*
X03554Y01891D02*
X03555Y0189D01*
X02705Y02298D02*
Y02319D01*
X03381Y01387D02*
X03422D01*
X01754Y02088D02*
Y02126D01*
X02803Y02307D02*
Y02358D01*
X03651Y01477D02*
X03652Y01478D01*
X02841Y02263D02*
Y02299D01*
X02252Y02518D02*
Y02613D01*
X03265Y01661D02*
X03272Y01654D01*
X03278Y01673D02*
X03492D01*
X03412Y0185D02*
X03491D01*
X01776Y01536D02*
X01776Y01536D01*
X01719Y01536D02*
X01719Y01536D01*
X02724Y02297D02*
X02726Y02295D01*
X02468Y02299D02*
Y02358D01*
Y02299D02*
X02475Y02292D01*
X03788Y01566D02*
X03894D01*
X01881Y02067D02*
X01884Y02071D01*
X03422Y01387D02*
X03431Y01378D01*
X02841Y02299D02*
X02862Y02319D01*
X02645Y02299D02*
X02646Y02299D01*
X02449Y02597D02*
X02463Y02612D01*
X02311Y02358D02*
X02331D01*
X0376Y01792D02*
X03804Y01836D01*
X03651Y01772D02*
X03715D01*
X02626Y02358D02*
Y02459D01*
X03234Y01752D02*
X03492D01*
X03831Y01478D02*
X03834Y01481D01*
X02409Y02314D02*
Y02358D01*
X03707Y02008D02*
X03719Y01996D01*
X01755Y02087D02*
X01776D01*
X03803Y01691D02*
X03804Y0169D01*
X0233Y02215D02*
X02331Y02215D01*
X03804Y01836D02*
Y0184D01*
X03411Y01831D02*
X03492D01*
X01798Y01304D02*
Y01318D01*
X03379Y01336D02*
X03383Y01339D01*
X02961Y02311D02*
Y02358D01*
X02272Y02463D02*
Y02518D01*
X02493Y02694D02*
X02494Y02696D01*
X02499Y02236D02*
X02527Y02264D01*
X02901Y02304D02*
Y02358D01*
X01776Y01614D02*
X01815D01*
X02429Y02322D02*
Y02358D01*
X03924Y01536D02*
D01*
X03779Y01575D02*
X03788Y01566D01*
X03491Y0185D02*
X03492Y01851D01*
X02705Y0232D02*
Y02358D01*
X02463Y02674D02*
X02484Y02694D01*
X03528Y0191D02*
X03554Y01936D01*
X02646Y02299D02*
Y02358D01*
X03272Y01654D02*
X03492D01*
Y01437D02*
X03492Y01438D01*
X02803Y02358D02*
X02803Y02358D01*
X02409Y02283D02*
X02429Y02303D01*
X03804Y01659D02*
Y0169D01*
X01797Y01319D02*
X01798Y01318D01*
X02702Y02293D02*
Y02295D01*
X02624Y02461D02*
X02626Y02459D01*
X02547Y02313D02*
X02579Y02281D01*
X03492Y0191D02*
X03528D01*
X02726Y02293D02*
Y02295D01*
X0245Y02282D02*
Y02284D01*
X03392Y01871D02*
X03412Y0185D01*
X03985Y03759D02*
X03987Y03758D01*
X03948Y03759D02*
X03985D01*
X03934Y03774D02*
Y04023D01*
Y03774D02*
X03948Y03759D01*
X03902Y03743D02*
X03958Y03687D01*
X03902Y03743D02*
Y04023D01*
X03871Y03758D02*
Y04023D01*
X038Y03687D02*
X03871Y03758D01*
X04185Y03701D02*
X04194Y0371D01*
X04167Y03701D02*
X04185D01*
X04194Y0371D02*
Y03774D01*
X04104Y0377D02*
X04108Y03774D01*
X04194*
X04103Y03771D02*
X04104Y0377D01*
X04066Y03771D02*
X04103D01*
X03987Y03758D02*
X04053D01*
X04066Y03771*
X02378Y02789D02*
X02449Y02718D01*
X0269D02*
X02692Y02721D01*
X02455Y02716D02*
X02684D01*
X03055Y00159D02*
Y00573D01*
Y00159D02*
X03057Y00157D01*
X02505Y00137D02*
X02507Y00139D01*
Y00271*
X02539Y00303D02*
Y00429D01*
X02507Y00271D02*
X02539Y00303D01*
X02503Y00464D02*
X02539Y00429D01*
X02503Y00464D02*
Y00573D01*
X0205Y00607D02*
X02503D01*
X01797Y00355D02*
X0205Y00607D01*
X02503D02*
X03055D01*
X03588Y02686D02*
Y0287D01*
X03534Y02888D02*
X03569D01*
X03588Y0287*
X03531Y02892D02*
X03534Y02888D01*
X04133Y01751D02*
X04134Y01751D01*
X04121Y01751D02*
X04133D01*
X04068Y01759D02*
X04113D01*
X04121Y01751*
X04171Y01751D02*
X04727Y02307D01*
X04134Y01751D02*
X04171D01*
X04243Y01623D02*
X04927Y02307D01*
X0415Y01623D02*
X04243D01*
X05061Y01074D02*
Y02407D01*
Y01074D02*
X05127Y01007D01*
X05211Y01133D02*
Y0234D01*
X05327Y01007D02*
Y01017D01*
X05211Y01133D02*
X05327Y01017D01*
X04873Y02595D02*
X05061Y02407D01*
X04893Y02658D02*
X05211Y0234D01*
X0492Y02714D02*
X05327Y02307D01*
X04729Y02714D02*
X0492D01*
X05577Y02214D02*
X05612D01*
X05634Y02236*
X04204Y03603D02*
X04275D01*
X03393Y03335D02*
X03431Y03297D01*
X03393Y03335D02*
Y03393D01*
X03392Y03395D02*
X03393Y03393D01*
X03328Y0327D02*
X0339Y03332D01*
X03431Y03297D02*
X03491D01*
X03205Y0327D02*
X03328D01*
X03425Y03666D02*
X03464D01*
X03349D02*
X03425D01*
X03424Y03636D02*
X03425Y03636D01*
Y03666*
X03464Y03648D02*
X03469Y03653D01*
X03608Y03727D02*
X03667Y03786D01*
X03589Y03727D02*
X03608D01*
X0096Y00714D02*
Y00718D01*
Y00714D02*
X00988Y00687D01*
X0099*
X00901Y00718D02*
Y00875D01*
X00932Y00906*
X04884Y02789D02*
X04887Y02786D01*
X04909Y02808D02*
D01*
X04794D02*
X04909D01*
X04794D02*
X04795Y02809D01*
X04909Y04118D02*
X0491Y04119D01*
X04909Y03961D02*
Y04118D01*
X03112Y03135D02*
X03183D01*
X03111Y03137D02*
X03112Y03135D01*
X0491Y04119D02*
Y04203D01*
X03209Y02834D02*
Y02896D01*
X03271Y02958*
X03191Y02824D02*
Y02924D01*
X0325Y02983*
Y03042*
X03269Y02795D02*
Y02814D01*
X0331Y03101D02*
X03487D01*
X03484Y03094D02*
X03491Y03101D01*
X03111Y03187D02*
X03111Y03187D01*
X03188*
X03188Y03187*
X03111Y03237D02*
X03172D01*
X03205Y0327*
X03111Y03287D02*
X03127D01*
X03134Y03294*
Y03344*
X02756Y03187D02*
X0284D01*
X02146Y02679D02*
Y02753D01*
X03333Y0319D02*
Y03206D01*
X03285Y03143D02*
X03333Y0319D01*
X03277Y03143D02*
X03285D01*
X03275Y03141D02*
X03277Y03143D01*
X02378Y0289D02*
X02387Y02899D01*
X02378Y02789D02*
Y0289D01*
X02387Y02958D02*
X02389Y0296D01*
Y03481*
X02333D02*
X02389D01*
X02329Y03484D02*
X02333Y03481D01*
X02452Y03563D02*
X02504D01*
X02264Y03545D02*
X02311D01*
X02329Y03563*
X02504Y03484D02*
X02578D01*
X02434Y03546D02*
X02452Y03563D01*
X02254Y03536D02*
X02264Y03545D01*
X02504Y03406D02*
X02634D01*
X02578Y03484D02*
X02579Y03486D01*
X00995Y02257D02*
X00996Y02256D01*
X00967Y0228D02*
X0099Y02257D01*
X00995*
X02212Y04074D02*
X02242D01*
X02253Y04086*
X02146Y04076D02*
X02147Y04074D01*
X02146Y04076D02*
Y04103D01*
X02147Y04074D02*
X02151D01*
X01346Y03978D02*
X01348Y0398D01*
X01408*
X01345Y04142D02*
X01346Y04141D01*
X01345Y04142D02*
Y04175D01*
X00959Y01743D02*
Y01747D01*
X00967Y0228D02*
Y02284D01*
X00904Y01224D02*
Y01402D01*
X00932Y01431*
X009Y01747D02*
Y01924D01*
X00908Y02284D02*
Y02456D01*
X00932Y02481*
X02151Y04014D02*
X0221D01*
X02043Y04057D02*
X02086Y04014D01*
X02151*
X01715Y03963D02*
X02245D01*
X02332Y04051D02*
Y0417D01*
X02245Y03963D02*
X02332Y04051D01*
X02358Y04022D02*
Y0417D01*
X02353Y04017D02*
X02358Y04022D01*
X01346Y04037D02*
Y04082D01*
Y04037D02*
X01356Y04047D01*
X0145*
X01457Y04053*
Y04153D02*
X01487Y04124D01*
X01569Y04171D02*
Y04173D01*
X01594Y04197*
X01659Y04019D02*
X01715Y03963D01*
X0325Y03042D02*
X0331Y03101D01*
X03208Y02815D02*
X03209Y02814D01*
X032Y02815D02*
X03208D01*
X03191Y02824D02*
X032Y02815D01*
X03229Y02845D02*
Y0288D01*
X04243Y02658D02*
X04893D01*
X0418Y02595D02*
X04243Y02658D01*
X04298Y02595D02*
X04873D01*
X04187Y02469D02*
X04912D01*
X04062Y02595D02*
X04187Y02469D01*
X04992Y01071D02*
Y02389D01*
X04912Y02469D02*
X04992Y02389D01*
X04927Y02307D02*
D01*
X04126Y01631D02*
X04142D01*
X0415Y01623*
X04927Y01007D02*
X04992Y01071D01*
X04068Y01659D02*
X04126D01*
X04179Y01601D02*
D01*
X04065Y01599D02*
X04068D01*
X04064Y01511D02*
Y01598D01*
Y0178D02*
X04065Y01779D01*
X04068Y01619D02*
X04117D01*
X04064Y01598D02*
X04065Y01599D01*
X04117Y01619D02*
X04135Y01601D01*
X0392Y01791D02*
X03944Y01816D01*
X04135Y01601D02*
X04179D01*
X04118Y01639D02*
X04126Y01631D01*
X04126Y01659D02*
X04134Y01651D01*
X03911Y01779D02*
X03919D01*
X04134Y01651D02*
X04134D01*
X04068Y01639D02*
X04118D01*
X0392Y0178D02*
Y01791D01*
X03919Y01779D02*
X0392Y0178D01*
X04065Y01779D02*
X04068D01*
X04064Y0178D02*
Y01796D01*
X01629Y04197D02*
X01631Y04199D01*
X01594Y04197D02*
X01629D01*
X01569Y04171D02*
D01*
X02527Y02518D02*
Y02582D01*
X02612Y02666D02*
X03568D01*
X02527Y02582D02*
X02612Y02666D01*
X03568D02*
X03588Y02686D01*
X01487Y04124D02*
X01631D01*
X03057Y0013D02*
X03059Y00132D01*
X01893Y04018D02*
X01903D01*
X01886Y04024D02*
X01893Y04018D01*
X01846Y04024D02*
X01886D01*
X02758Y03661D02*
X02797Y03701D01*
X02719Y03661D02*
X02758D01*
X02797Y03701D02*
X03D01*
X03979Y00808D02*
Y0089D01*
X03895Y00724D02*
X03979Y00808D01*
X03737Y00724D02*
X03895D01*
X06679Y02339D02*
Y0242D01*
X06643Y02302D02*
X06679Y02339D01*
X06469Y02302D02*
X06643D01*
X06435D02*
X06469D01*
X06397Y02341D02*
X06435Y02302D01*
X06352Y02341D02*
X06397D01*
X06788Y01881D02*
X06804D01*
X06782Y01874D02*
X06788Y01881D01*
X06782Y01874D02*
Y01816D01*
X06897D02*
Y01864D01*
X0688Y01881D02*
X06897Y01864D01*
X06832Y01881D02*
X0688D01*
X06359Y0331D02*
X06388D01*
X06336Y03287D02*
X06359Y0331D01*
X06336Y03267D02*
Y03287D01*
X0649Y03172D02*
X06511D01*
X06489Y03173D02*
X0649Y03172D01*
X0642Y0313D02*
Y0315D01*
X0641Y03121D02*
X0642Y0313D01*
X06304Y03121D02*
X0641D01*
X01017Y03836D02*
X02029D01*
X0084Y04013D02*
X01017Y03836D01*
X00835Y03816D02*
X02004D01*
X00638Y04012D02*
X00835Y03816D01*
X00638Y04012D02*
Y04038D01*
X01363Y03896D02*
X02084D01*
X01243Y04015D02*
X01363Y03896D01*
X01243Y04015D02*
Y04038D01*
X01185Y03871D02*
X02059D01*
X01042Y04014D02*
X01185Y03871D01*
X01042Y04014D02*
Y04038D01*
X0084Y04013D02*
Y04038D01*
X01774Y04049D02*
X01846D01*
X01676Y04147D02*
X01774Y04049D01*
X01633Y04147D02*
X01676D01*
X02146Y02578D02*
Y02624D01*
X02108Y0254D02*
X02146Y02578D01*
X02108Y01728D02*
Y0254D01*
X06604Y03192D02*
X06704D01*
X06726Y0317*
Y03168D02*
Y0317D01*
X06604Y03191D02*
X06604Y03192D01*
X06511Y03191D02*
X06604D01*
X06604Y03264D02*
X06704D01*
X06726Y03286*
Y03294*
X06604Y03263D02*
Y03264D01*
X06552Y03211D02*
X06604Y03263D01*
X06511Y03211D02*
X06552D01*
X00644Y04099D02*
Y04197D01*
X00638Y04093D02*
X00644Y04099D01*
X00846D02*
Y04192D01*
X0084Y04093D02*
X00846Y04099D01*
X03053Y00571D02*
X03055Y00573D01*
X06234Y02183D02*
Y02241D01*
X06184Y02291D02*
X06234Y02241D01*
X06157Y02291D02*
X06184D01*
X06804Y01881D02*
X06832D01*
X06122Y02433D02*
X06128D01*
X06138Y02423*
Y02418D02*
Y02423D01*
Y02418D02*
X06147Y02409D01*
Y02398D02*
Y02409D01*
Y02398D02*
X06154Y02391D01*
X06157*
X06184*
X06244Y02451*
X06312*
X02944Y03745D02*
Y03951D01*
X03144Y03745D02*
Y03951D01*
X03349Y03745D02*
Y03946D01*
X03344Y03951D02*
X03349Y03946D01*
X04112Y03701D02*
Y03706D01*
X04085Y03733D02*
X04112Y03706D01*
X03987Y03733D02*
X04085D01*
X01846Y04074D02*
X01933D01*
X01933Y04074*
X03827Y03808D02*
X03829Y03806D01*
X03772Y03808D02*
X03827D01*
X01631Y04149D02*
X01633Y04147D01*
X06379Y03309D02*
X06388D01*
X06388Y0331D02*
X06388Y03309D01*
X06334Y03266D02*
Y03269D01*
Y03266D02*
X06336Y03267D01*
X06347Y0325D02*
X06388D01*
X06343Y03246D02*
X06347Y0325D01*
X06302Y03246D02*
X06343D01*
X01897Y01516D02*
X02108Y01728D01*
X02141Y02624D02*
X02146D01*
X01631Y04024D02*
X01653D01*
X01658Y04019*
X01659*
X03484Y03051D02*
Y03094D01*
X0351Y03395D02*
X03518Y03403D01*
Y03437*
X06362Y03231D02*
X06388D01*
X06331Y03201D02*
X06362Y03231D01*
X06447Y03396D02*
X06459Y03383D01*
Y03332D02*
Y03383D01*
X02829Y03655D02*
X02834Y03661D01*
X02829Y03645D02*
Y03655D01*
X02799Y03616D02*
X02829Y03645D01*
X03589Y01711D02*
X03591D01*
X00932Y00906D02*
X01004D01*
X00932Y01431D02*
X01007D01*
X01008Y0143*
X00932Y01956D02*
X01009D01*
X00932Y02481D02*
X0102D01*
X03469Y03653D02*
Y03661D01*
X03242Y03659D02*
X03244Y03661D01*
X03242Y03598D02*
Y03659D01*
X03239Y03596D02*
X03242Y03598D01*
X0268Y03661D02*
X02719D01*
X02679Y03661D02*
X0268Y03661D01*
X03701Y03752D02*
Y03786D01*
X03699Y03751D02*
X03701Y03752D01*
Y03837D02*
Y03861D01*
X03699Y03836D02*
X03701Y03837D01*
X03772Y03683D02*
X03794D01*
X03799Y03687*
X038*
X03964Y03683D02*
X03987D01*
X0396Y03687D02*
X03964Y03683D01*
X03958Y03687D02*
X0396D01*
X03Y03701D02*
X03035Y03666D01*
X03044*
X06459Y0315D02*
X0646Y0315D01*
Y03164*
X06469Y03173*
X06489*
X0644Y0315D02*
Y0319D01*
X06439Y03191D02*
X0644Y0319D01*
X06354Y03331D02*
X06356Y03329D01*
X06388*
X0642Y03332D02*
X06421Y03331D01*
Y03314D02*
Y03331D01*
Y03314D02*
X06444Y03291D01*
X06409Y03371D02*
X06424D01*
X0644Y03355*
Y03332D02*
Y03355D01*
X06479Y03425D02*
X06479Y03426D01*
X06509Y03456D02*
X06511Y03454D01*
Y03329D02*
Y03454D01*
X06479Y03332D02*
Y03425D01*
X02839Y03666D02*
X02944D01*
X02834Y03661D02*
X02839Y03666D01*
X03044Y03745D02*
Y03951D01*
X03144Y03666D02*
X03239D01*
X03244Y03661*
X03464Y03666D02*
X03469Y03661D01*
X03667Y03786D02*
X03668D01*
X03667Y03861D02*
X03668D01*
X03618Y03909D02*
X03667Y03861D01*
X03589Y03909D02*
X03618D01*
X03701Y03861D02*
X03702Y03859D01*
X03771*
X03772Y03858*
X03701Y03786D02*
X03702Y03784D01*
X03771*
X03772Y03783*
X00594Y02481D02*
X00932D01*
X00199D02*
X00594D01*
X06832Y02031D02*
X06836D01*
X06843Y02038*
Y02096*
X06749Y02035D02*
Y02088D01*
Y02035D02*
X06804Y01981D01*
X06832*
X06481Y01954D02*
X06519D01*
X06369Y01842D02*
X06481Y01954D01*
X06319Y01842D02*
X06369D01*
X06542Y01931D02*
X06637D01*
X06519Y01953D02*
X06542Y01931D01*
X06519Y01953D02*
Y01954D01*
X06533Y02031D02*
X06637D01*
X06519Y02017D02*
X06533Y02031D01*
X06064Y02344D02*
X06067Y02341D01*
X06156Y02171D02*
Y0224D01*
X06157Y02241*
X06352D02*
X06468D01*
X06469Y02239*
X0651Y03071D02*
Y03076D01*
X0646Y03126D02*
X0651Y03076D01*
X0646Y03126D02*
Y03149D01*
X06459Y0315D02*
X0646Y03149D01*
X01048Y04099D02*
Y04192D01*
X01042Y04093D02*
X01048Y04099D01*
X01249D02*
Y04192D01*
X01243Y04093D02*
X01249Y04099D01*
G54D24*
X06605Y03129D02*
X06647D01*
X06604Y03129D02*
X06605Y03129D01*
X06487Y03125D02*
X06551D01*
X06479Y03132D02*
X06487Y03125D01*
X06479Y03132D02*
Y03143D01*
X06555Y03129D02*
X06604D01*
X06551Y03125D02*
X06555Y03129D01*
X06479Y03143D02*
X06479Y03143D01*
G54D26*
X02545Y00137D03*
X02466D03*
X02348D03*
X0282D03*
X01915D03*
X02033D03*
X02663D03*
X02702D03*
X0286D03*
X02978D03*
X0219D03*
X01994D03*
X01954D03*
X03017D03*
X02309D03*
X02112D03*
X02151D03*
X02387D03*
X02427D03*
X02584D03*
X02624D03*
X02742D03*
X02781D03*
X02899D03*
X02938D03*
X02505D03*
X02072D03*
X01797D03*
X01836D03*
X01875D03*
X03096D03*
G54D27*
X03057Y00157D03*
G54D28*
X0415Y03603D03*
X04204D03*
X04638Y04204D03*
X04692D03*
X03532Y02797D03*
X03477D03*
X0609Y03556D03*
X06035D03*
X06842Y01816D03*
X06897D03*
X06736Y01818D03*
X0679D03*
X06311Y0246D03*
X06365D03*
X04112Y03701D03*
X04167D03*
X05161Y04208D03*
X05216D03*
X04638Y04149D03*
X04692D03*
G54D29*
X00966Y0072D03*
X00907D03*
X05159Y04153D03*
X05218D03*
X00966Y01216D03*
X00907D03*
X00959Y01747D03*
X009D03*
X0097Y02275D03*
X00911D03*
G54D30*
X00653Y01894D03*
Y0201D03*
Y02422D03*
Y02538D03*
Y00847D03*
Y00963D03*
Y01375D03*
Y01491D03*
G54D31*
X00713Y01952D03*
Y0248D03*
Y00905D03*
Y01433D03*
G54D32*
X01248Y04052D03*
Y04105D03*
X01047Y04052D03*
Y04105D03*
X00846Y04052D03*
Y04105D03*
X00641Y04052D03*
Y04105D03*
G54D33*
X02209Y03716D03*
Y03645D03*
X04339Y02851D03*
Y0278D03*
X06334Y02181D03*
Y0211D03*
X06659Y02095D03*
Y02166D03*
X06275Y02822D03*
Y02893D03*
X06362Y02822D03*
Y02893D03*
X04104Y03841D03*
Y0377D03*
X02639Y03606D03*
Y03535D03*
X03693Y03117D03*
Y03188D03*
X04064Y02851D03*
Y0278D03*
X03959Y02851D03*
Y0278D03*
X04234Y02851D03*
Y0278D03*
G54D34*
X06679Y0242D03*
Y02802D03*
X06319Y0146D03*
Y01842D03*
G54D35*
X06687Y01611D03*
X06632D03*
X06687Y01671D03*
X06632D03*
X06687Y01721D03*
X06632D03*
X06687Y01776D03*
X06632D03*
X06152Y02171D03*
X06097D03*
X06847Y02096D03*
X06902D03*
X0372Y00645D03*
X03665D03*
X06314Y02673D03*
X0637D03*
X06314Y02606D03*
X0637D03*
X06314Y02535D03*
X0637D03*
X06314Y0274D03*
X0637D03*
X05622Y03358D03*
X05677D03*
G54D36*
X04394Y03929D03*
X04439D03*
G54D37*
X03125Y02787D03*
Y02732D03*
X03358Y02791D03*
Y02736D03*
X04523Y03846D03*
Y03791D03*
X04454Y03033D03*
Y03088D03*
X04394Y03033D03*
Y03088D03*
X04334Y03033D03*
Y03088D03*
X04274Y03033D03*
Y03088D03*
X04219Y03033D03*
Y03088D03*
X04164Y03033D03*
Y03088D03*
X04109Y03033D03*
Y03088D03*
X03771Y03137D03*
Y03082D03*
X0272Y03598D03*
Y03543D03*
X02139Y03653D03*
Y03708D03*
X06586Y03059D03*
Y03003D03*
G54D38*
X04375Y0386D03*
X0445D03*
Y03776D03*
X04413D03*
G54D39*
X04375Y03776D03*
G54D40*
X0371Y03786D03*
X03659D03*
X0371Y03861D03*
X03659D03*
G54D41*
X06064Y02387D03*
Y02334D03*
X06939Y01879D03*
Y01932D03*
G54D42*
X02212Y01037D03*
X0298Y02357D03*
X02586Y02517D03*
X02488D03*
X02389D03*
X02291D03*
X02881Y02357D03*
X02783D03*
X02685D03*
X02586D03*
X02488D03*
X02389D03*
X02291D03*
X0294D03*
X0296D03*
X02901D03*
X02921D03*
X02842D03*
X02862D03*
X02803D03*
X02822D03*
X02744D03*
X02763D03*
X02704D03*
X02724D03*
X02645D03*
X02665D03*
X02606D03*
X02625D03*
X02547D03*
X02566D03*
X02507D03*
X02527D03*
X02448D03*
X02468D03*
X02409D03*
X02429D03*
X0235D03*
X0237D03*
X02212Y02517D03*
X02232D03*
Y02357D03*
X02212D03*
X02251Y02517D03*
X02271D03*
X02409D03*
X02429D03*
X0235D03*
X0237D03*
X02507D03*
X02527D03*
X02448D03*
X02468D03*
X02606D03*
X02547D03*
X02625D03*
X02566D03*
X02251Y02357D03*
X02311D03*
X0233D03*
X02271D03*
X02311Y02517D03*
X0233D03*
X02803Y01037D03*
X02822D03*
X02862Y00877D03*
X02881D03*
X02744D03*
X02763D03*
X02685Y01037D03*
X02704D03*
X02586Y00877D03*
Y01037D03*
X02645Y00877D03*
X02625D03*
X02744Y01037D03*
X02763D03*
X02803Y00877D03*
X02822D03*
X02685D03*
X02704D03*
X02625Y01037D03*
X02645D03*
X02232Y00877D03*
X02429D03*
X0237D03*
X0235D03*
X0233D03*
X02291D03*
X02389D03*
X02488D03*
X02527D03*
X02547D03*
X02566D03*
X02448D03*
X02468D03*
X02251D03*
X02271D03*
X02566Y01037D03*
X0237D03*
X02389D03*
X02429D03*
X02468D03*
X02488D03*
X02448D03*
X02291D03*
X02271D03*
X02251D03*
X02232D03*
X0235D03*
X0233D03*
X02547D03*
X02527D03*
X02862D03*
X02881D03*
X02921Y00877D03*
Y01037D03*
X0294Y00877D03*
Y01037D03*
X0298Y00877D03*
Y01037D03*
X0296D03*
Y00877D03*
X02901Y01037D03*
X02842D03*
X02783D03*
X02724D03*
X02665D03*
X02606D03*
X02507D03*
X02409D03*
X02311D03*
X02901Y00877D03*
X02842D03*
X02783D03*
X02724D03*
X02665D03*
X02606D03*
X02507D03*
X02409D03*
X02311D03*
X02212D03*
X02645Y02517D03*
X02665D03*
X02685D03*
X02704D03*
X02724D03*
X02744D03*
X02763D03*
X02783D03*
X02803D03*
X02822D03*
X02842D03*
X02862D03*
X02881D03*
X02901D03*
X02921D03*
X0294D03*
X0296D03*
X0298D03*
G54D43*
X01696Y01262D03*
X0357D03*
X01696Y02142D03*
X0357D03*
G54D44*
X02156Y02437D03*
Y00957D03*
X03036D03*
Y02437D03*
G54D45*
X03491Y01397D03*
Y01377D03*
Y01456D03*
Y01476D03*
Y01771D03*
Y01495D03*
Y01791D03*
Y01889D03*
Y0185D03*
Y01869D03*
Y0183D03*
X03651Y01869D03*
Y01889D03*
Y01928D03*
X03491Y01338D03*
Y01358D03*
X03651Y01791D03*
Y01771D03*
Y0185D03*
Y0183D03*
Y01948D03*
Y01988D03*
Y01968D03*
X03491Y01988D03*
Y01968D03*
X03651Y01692D03*
X03491Y01633D03*
Y01673D03*
Y01653D03*
Y01692D03*
X03651Y01732D03*
Y01751D03*
Y01653D03*
Y01574D03*
Y01554D03*
Y01673D03*
Y01633D03*
X03491Y01928D03*
Y01554D03*
Y02007D03*
Y01909D03*
Y0181D03*
Y01712D03*
Y01613D03*
Y01515D03*
Y01417D03*
X03651Y02007D03*
Y01909D03*
Y0181D03*
Y01712D03*
Y01613D03*
Y01515D03*
Y01417D03*
X03491Y01948D03*
X03651Y01594D03*
X03491Y01535D03*
X03651Y01495D03*
Y01476D03*
Y01456D03*
Y01436D03*
Y01397D03*
Y01377D03*
Y01358D03*
Y01338D03*
X03491Y01318D03*
X03651D03*
X03491Y01732D03*
Y01751D03*
X03651Y01535D03*
X03491Y01574D03*
Y01594D03*
Y01436D03*
Y02086D03*
Y02066D03*
Y02047D03*
Y02027D03*
X03651Y02086D03*
Y02066D03*
Y02047D03*
Y02027D03*
X01776Y01633D03*
Y01614D03*
Y01869D03*
Y02027D03*
Y01909D03*
Y0183D03*
Y01948D03*
Y01732D03*
Y01771D03*
X01616Y01928D03*
Y0185D03*
Y01909D03*
Y02027D03*
X01776Y02007D03*
Y01968D03*
Y01456D03*
Y01673D03*
X01616Y01869D03*
Y01968D03*
X01776Y01928D03*
Y0185D03*
Y0181D03*
Y01653D03*
X01616Y02007D03*
X01776Y01751D03*
Y01712D03*
X01616Y01948D03*
X01776Y01554D03*
Y01574D03*
X01616Y01515D03*
Y01456D03*
Y0181D03*
Y0183D03*
X01776Y01436D03*
X01616Y01358D03*
X01776Y01338D03*
X01616Y01574D03*
Y01436D03*
Y01535D03*
Y01554D03*
Y01614D03*
Y01732D03*
Y01673D03*
Y01377D03*
Y01476D03*
Y01417D03*
Y01751D03*
X01776Y01358D03*
X01616Y01338D03*
Y01633D03*
Y01771D03*
X01776Y01377D03*
Y01318D03*
Y01417D03*
X01616Y01318D03*
X01776Y01476D03*
X01616Y01712D03*
Y01653D03*
X01776Y01515D03*
X01616Y02047D03*
X01776D03*
Y01397D03*
Y01495D03*
Y01594D03*
Y01692D03*
Y01791D03*
Y01889D03*
Y01988D03*
X01616Y01397D03*
Y01495D03*
Y01594D03*
Y01692D03*
Y01791D03*
Y01889D03*
Y01988D03*
Y02086D03*
X01776D03*
Y02066D03*
Y01535D03*
X01616Y02066D03*
G54D46*
X03111Y02937D03*
Y02987D03*
Y03037D03*
Y03087D03*
Y03137D03*
Y03187D03*
Y03237D03*
Y03287D03*
X02756Y02937D03*
Y02987D03*
Y03037D03*
Y03087D03*
Y03137D03*
Y03187D03*
Y03237D03*
Y03287D03*
G54D47*
X02199Y04275D03*
X02465D03*
G54D48*
X02281Y0417D03*
X02306D03*
X02332D03*
X02358D03*
X02383D03*
G54D49*
X0243Y04173D03*
X02234D03*
G54D50*
X02377Y04275D03*
G54D51*
X02271Y04275D03*
G54D52*
X03808Y04023D03*
X03839D03*
X03871D03*
X03902D03*
X03934D03*
G54D53*
X03696Y04244D03*
Y04027D03*
X04046D03*
Y04244D03*
G54D54*
X03495Y0375D03*
X03444D03*
X03469Y03661D03*
X0286Y0375D03*
X02809D03*
X02834Y03661D03*
X02745Y0375D03*
X02694D03*
X02719Y03661D03*
X0327Y0375D03*
X03219D03*
X03244Y03661D03*
G54D55*
X01631Y04199D03*
Y04174D03*
Y04149D03*
Y04124D03*
Y04099D03*
Y04074D03*
Y04049D03*
Y04024D03*
X01846Y04199D03*
Y04174D03*
Y04149D03*
Y04124D03*
Y04099D03*
Y04074D03*
Y04049D03*
Y04024D03*
X03772Y03858D03*
Y03833D03*
Y03808D03*
Y03783D03*
Y03758D03*
Y03733D03*
Y03708D03*
Y03683D03*
X03987Y03858D03*
Y03833D03*
Y03808D03*
Y03783D03*
Y03758D03*
Y03733D03*
Y03708D03*
Y03683D03*
G54D56*
X06157Y02241D03*
Y02291D03*
Y02341D03*
Y02391D03*
X06352D03*
Y02341D03*
Y02291D03*
Y02241D03*
X06832Y02031D03*
Y01981D03*
Y01931D03*
Y01881D03*
X06637D03*
Y01931D03*
Y01981D03*
Y02031D03*
G54D57*
X06197Y03701D03*
X06341D03*
X05887D03*
X06031D03*
X06346Y03566D03*
X06202D03*
G54D58*
X06726Y03294D03*
X06943D03*
Y03168D03*
X06726D03*
G54D59*
X03569Y03385D03*
G54D60*
X03392Y03395D03*
X0351Y03206D03*
X03333D03*
Y03395D03*
X03569Y03206D03*
X0351Y03395D03*
X03451D03*
X03392Y03206D03*
X03451D03*
G54D61*
X03525Y02995D03*
Y02948D03*
X03444D03*
Y02995D03*
G54D62*
X03484Y03051D03*
Y02892D03*
G54D63*
X03531Y02892D03*
Y03051D03*
X03438Y02892D03*
Y03051D03*
G54D64*
X02944Y03951D03*
Y04221D03*
X03044Y03951D03*
Y04221D03*
X03144Y03951D03*
Y04221D03*
X03244Y03951D03*
Y04221D03*
X03344Y03951D03*
Y04221D03*
G54D65*
X03349Y03745D03*
Y03666D03*
X02944Y03745D03*
Y03666D03*
X03044Y03745D03*
Y03666D03*
X03144Y03745D03*
Y03666D03*
G54D66*
X05091Y04206D03*
X04957D03*
X04566D03*
X04432D03*
G54D67*
X04068Y01779D03*
X03911D03*
X04068Y01759D03*
X03911D03*
X04068Y01739D03*
X03911D03*
X04068Y01719D03*
X03911D03*
X04068Y01699D03*
X03911D03*
X04068Y01679D03*
X03911D03*
X04068Y01659D03*
X03911D03*
X04068Y01639D03*
X03911D03*
X04068Y01619D03*
X03911D03*
Y01599D03*
X04068D03*
G54D68*
X06479Y0315D03*
X06459D03*
X0644D03*
X0642D03*
Y03332D03*
X0644D03*
X06459D03*
X06479D03*
G54D69*
X06511Y03152D03*
X06388D03*
Y03172D03*
Y03191D03*
Y03211D03*
Y03231D03*
Y0325D03*
Y0327D03*
Y0329D03*
Y03309D03*
Y03329D03*
X06511D03*
Y03309D03*
Y0329D03*
Y0327D03*
Y0325D03*
Y03231D03*
Y03211D03*
Y03172D03*
Y03191D03*
G54D70*
X04149Y02842D03*
Y02789D03*
X04434Y02842D03*
Y02789D03*
G54D71*
X04909Y02808D03*
Y03961D03*
G54D72*
X00932Y00906D03*
X01157D03*
Y01956D03*
X00932D03*
X01157Y02481D03*
X00932D03*
Y01431D03*
X01157D03*
G54D73*
X01249Y04197D03*
Y04254D03*
X03589Y03909D03*
Y03852D03*
Y03727D03*
Y03784D03*
X00644Y04254D03*
Y04197D03*
X00846Y04254D03*
Y04197D03*
X01048D03*
Y04254D03*
G54D74*
X04039Y03092D03*
Y03029D03*
X06469Y02302D03*
Y02239D03*
X06519Y02017D03*
Y01954D03*
X04194Y03837D03*
Y03774D03*
X03688Y03329D03*
Y03266D03*
X06604Y03327D03*
Y03264D03*
Y03129D03*
Y03192D03*
G54D75*
X03249Y02845D03*
X03229D03*
Y02784D03*
X03249D03*
G54D76*
X03209Y02834D03*
Y02814D03*
Y02795D03*
X03269D03*
Y02814D03*
Y02834D03*
G54D77*
X05812Y03361D03*
X05741D03*
X067Y01421D03*
X06629D03*
X067Y01531D03*
X06629D03*
X0651Y03071D03*
X06439D03*
X03659Y00726D03*
X0373D03*
X01873Y04276D03*
X01802D03*
X04209Y03246D03*
X0428D03*
G54D78*
X04332Y03603D03*
X04275D03*
G54D79*
X06749Y02088D03*
Y02143D03*
X06234Y02128D03*
Y02183D03*
X07Y01878D03*
Y01932D03*
X06003Y02335D03*
Y02389D03*
X02146Y02679D03*
Y02624D03*
X06122Y02433D03*
Y02488D03*
X01933Y04129D03*
Y04074D03*
G54D80*
X02503Y00573D03*
Y00607D03*
X03055Y00573D03*
Y00607D03*
G54D81*
X02509Y0364D03*
Y03483D03*
Y03562D03*
Y03404D03*
X02334Y0364D03*
Y03562D03*
Y03483D03*
Y03404D03*
G54D82*
X01727Y04273D03*
X01664D03*
G54D83*
X01346Y04141D03*
Y04082D03*
Y03978D03*
Y04037D03*
X02151Y04074D03*
Y04015D03*
X02212Y04074D03*
Y04015D03*
X02387Y02958D03*
Y02899D03*
G54D142*
X00299Y02581D03*
Y02381D03*
X00099D03*
Y02581D03*
X00299Y02056D03*
Y01856D03*
X00099D03*
Y02056D03*
X00299Y01531D03*
Y01331D03*
X00099D03*
Y01531D03*
X00299Y01006D03*
Y00806D03*
X00099D03*
Y01006D03*
G54D162*
X06822Y01776D02*
D01*
X06824Y01776*
X06825Y01776*
X06827Y01776*
X06828Y01776*
X06829Y01777*
X06831Y01777*
X06832Y01778*
X06833Y01779*
X06834Y01779*
X06835Y0178*
X06836Y01781*
X06837Y01781*
X02974Y00224D02*
D01*
X02974Y00226*
X02974Y00227*
X02974Y00228*
X02973Y0023*
X02973Y00231*
X02972Y00232*
X02972Y00234*
X02971Y00235*
X0297Y00236*
X02969Y00237*
X02969Y00237*
X02467Y00217D02*
D01*
X02467Y00218*
X02467Y0022*
X02466Y00221*
X02466Y00222*
X02466Y00224*
X02465Y00225*
X02464Y00226*
X02464Y00227*
X02463Y00229*
X02462Y0023*
X02461Y00231*
X0246Y00232*
X02459Y00233*
X02459Y00233*
X03725Y0065D02*
Y00721D01*
X0373Y00726*
X0372Y00645D02*
X03725Y0065D01*
X04332Y03603D02*
X04677D01*
X03752Y03188D02*
X03771Y03169D01*
Y03137D02*
Y03169D01*
X03693Y03188D02*
X03752D01*
X03691Y03191D02*
Y03264D01*
X03688Y03266D02*
X03691Y03264D01*
Y03191D02*
X03693Y03188D01*
X04516Y03044D02*
X04547Y03074D01*
X04449Y03246D02*
X04547Y03148D01*
X04109Y03044D02*
X04516D01*
X0516Y04154D02*
Y04207D01*
X05159Y04153D02*
X0516Y04154D01*
Y04207D02*
X05161Y04208D01*
X02139Y03611D02*
Y03663D01*
X02761Y03592D02*
X02774Y03579D01*
X02659Y03592D02*
X02761D01*
X02774Y03566D02*
Y03579D01*
X0272Y03494D02*
X0272Y03495D01*
Y03553*
X06837Y01781D02*
X06838Y01783D01*
X06837Y01781D02*
D01*
X06687Y01776D02*
X06822D01*
X02504Y03642D02*
X02598D01*
X04638Y04149D02*
Y04204D01*
Y04149D02*
D01*
X05091Y04206D02*
X05094Y04208D01*
X05161*
X05285D02*
X05299Y04223D01*
X05216Y04208D02*
X05285D01*
X05299Y03537D02*
Y04223D01*
X04566Y04206D02*
X04568Y04204D01*
X04638*
X04692D02*
X04692Y04205D01*
Y04255*
X04713Y04276*
X05622Y03313D02*
X05633Y03302D01*
X05622Y03358D02*
D01*
Y03313D02*
Y03358D01*
X05633Y03302D02*
X05812D01*
X05847D02*
X05964Y03419D01*
Y03555*
X05965Y03556D02*
X06035D01*
X05964Y03555D02*
X05965Y03556D01*
X06275Y02893D02*
Y02948D01*
X06274Y02949D02*
X06275Y02948D01*
X06362Y02893D02*
Y02952D01*
X0651Y03071D02*
X06518Y03062D01*
X06582D02*
X06586Y03059D01*
X06518Y03062D02*
X06582D01*
X06585Y03059D02*
X06586D01*
X06196Y02484D02*
X06248Y02535D01*
X06122Y02488D02*
X06189D01*
X06193Y02484D02*
X06196D01*
X06248Y02535D02*
X06314D01*
X06189Y02488D02*
X06193Y02484D01*
X06312Y02533D02*
X06314Y02535D01*
X06304Y02735D02*
X06314Y02724D01*
X06304Y02735D02*
Y0277D01*
X0354Y03715D02*
Y03806D01*
X03219Y0375D02*
Y03826D01*
X06314Y02536D02*
Y02606D01*
Y02673*
Y02724*
X06279Y02795D02*
X06304Y0277D01*
X06279Y02795D02*
Y02818D01*
X06275Y02822D02*
X06279Y02818D01*
X06362Y02822D02*
X0646D01*
X06275D02*
X06362D01*
X0646D02*
X06492Y02791D01*
X06687Y01721D02*
Y01776D01*
Y01671D02*
Y01721D01*
Y01611D02*
Y01671D01*
Y01611D02*
X06692Y01605D01*
Y01538D02*
X067Y01531D01*
X06692Y01538D02*
Y01605D01*
X067Y01421D02*
Y01531D01*
X06838Y01649D02*
Y01783D01*
X06842Y01787*
Y01816*
X02957Y00251D02*
X02969Y00237D01*
X02974Y00141D02*
Y00224D01*
D01*
X02467Y00111D02*
Y00217D01*
D01*
X02447Y00242D02*
X02459Y00233D01*
X03097Y00111D02*
X03097Y00111D01*
Y00251*
X02636Y00247D02*
X0269D01*
X02637Y00247D02*
X02651D01*
X02636Y00247D02*
X02637Y00247D01*
X02702Y0018D02*
X02703Y00179D01*
X0269Y00247D02*
X02702Y00236D01*
X02703Y00111D02*
Y00179D01*
X02974Y00141D02*
X02978Y00137D01*
X06346Y03566D02*
X06381D01*
X06414Y03599*
Y03726*
X06565Y03802D02*
X06569Y03806D01*
X0649Y03802D02*
X06565D01*
X06414Y03726D02*
X0649Y03802D01*
X02545Y00244D02*
X02546Y00244D01*
X02545Y00111D02*
Y00244D01*
X01815Y00257D02*
X01835D01*
X02856Y00141D02*
Y00233D01*
X02347Y00112D02*
X02349Y00111D01*
X02837Y00251D02*
X02856Y00233D01*
X02347Y00112D02*
Y00237D01*
X02034Y00111D02*
Y00245D01*
X02817Y00141D02*
X0282Y00137D01*
X02817Y00141D02*
Y00233D01*
X02338Y00246D02*
X02347Y00237D01*
X02651Y00247D02*
X02663Y00235D01*
X02702Y00138D02*
X02702Y00137D01*
X02702Y00138D02*
Y0018D01*
X02663Y00137D02*
Y00235D01*
X02034Y00245D02*
X02034Y00246D01*
X02309D02*
X02338D01*
X02856Y00141D02*
X0286Y00137D01*
X02799Y00251D02*
X02837D01*
X02702Y0018D02*
Y00236D01*
X02799Y00251D02*
X02817Y00233D01*
X01915Y00111D02*
Y00244D01*
Y00111D02*
X01916Y00111D01*
X02073D02*
X02076Y00114D01*
X03466Y03806D02*
X03539D01*
X03444Y0375D02*
Y03783D01*
X03466Y03806*
X03589Y03784D02*
Y03827D01*
X0354Y03806D02*
X03569D01*
X03589Y03827*
Y03852*
X0354Y03806D02*
X0354Y03806D01*
X03539Y03806D02*
X0354Y03806D01*
Y03715D02*
X03654Y03601D01*
X04331Y03604D02*
X04332Y03603D01*
X04331Y03604D02*
Y03631D01*
X0431Y03653D02*
X04331Y03631D01*
X04057Y03601D02*
X04109Y03653D01*
X0431*
X03654Y03601D02*
X04057D01*
X04677Y03603D02*
X04768Y03511D01*
X05274*
X02321Y03397D02*
X02329Y03406D01*
X02321Y03361D02*
Y03397D01*
X05274Y03511D02*
X05274Y03511D01*
X0588Y03701D02*
X05887Y03708D01*
X05722Y03783D02*
Y03844D01*
X06094Y03554D02*
Y03565D01*
X05725Y04033D02*
X05829Y04137D01*
X05812Y03302D02*
X05847D01*
X05812D02*
Y03361D01*
X06744Y02143D02*
X0675Y02148D01*
X06293Y02181D02*
X06424D01*
X062Y03568D02*
X06202Y03566D01*
X062Y03568D02*
Y03586D01*
X06197Y03588D02*
Y03701D01*
Y03588D02*
X062Y03586D01*
X06734Y03806D02*
X069D01*
X06569D02*
X06734D01*
X02084Y00271D02*
X02112D01*
X02072Y00259D02*
X02084Y00271D01*
X02072Y00137D02*
Y00259D01*
X01876Y00111D02*
Y0024D01*
X01846Y00267D02*
X01849D01*
X01837Y00111D02*
Y00255D01*
X01798Y00111D02*
Y00239D01*
X01815Y00257*
X01837Y00255D02*
X01849Y00267D01*
X01835Y00257D02*
X01846Y00267D01*
X06364Y0133D02*
X06667D01*
X06319Y01375D02*
X06364Y0133D01*
X06319Y01375D02*
Y0146D01*
X067Y01363D02*
Y01421D01*
X06667Y0133D02*
X067Y01363D01*
X06712Y02001D02*
Y02114D01*
X06691Y01981D02*
X06712Y02001D01*
X06637Y01981D02*
X06691D01*
X06712Y02135D02*
X0672Y02143D01*
X06712Y02114D02*
Y02135D01*
X067Y02102D02*
X06712Y02114D01*
X06666Y02102D02*
X067D01*
X06659Y02095D02*
X06666Y02102D01*
X0672Y02143D02*
X06744D01*
X06749*
X0671Y0222D02*
X0675Y02181D01*
Y02148D02*
Y02181D01*
X06587Y0222D02*
X0671D01*
X06547Y02181D02*
X06587Y0222D01*
X06281Y02149D02*
Y02192D01*
X06264Y02133D02*
X06281Y02149D01*
X06239Y02133D02*
X06264D01*
X06234Y02128D02*
X06239Y02133D01*
X06281Y02192D02*
X06293Y02181D01*
X06281Y02192D02*
Y02271D01*
X063Y02291*
X06352*
X06492Y02791D02*
X06669D01*
X06679Y02802*
X06549Y02929D02*
X06639D01*
X0651Y02968D02*
X06549Y02929D01*
X0651Y02968D02*
Y03071D01*
X06679Y02802D02*
Y02889D01*
X06639Y02929D02*
X06679Y02889D01*
X062Y03708D02*
X06226D01*
X06197Y03705D02*
X062Y03708D01*
X06197Y03701D02*
Y03705D01*
X06226Y03708D02*
X06253Y03736D01*
Y0409*
X06207Y04137D02*
X06253Y0409D01*
X05829Y04137D02*
X06207D01*
X06094Y03554D02*
X0615D01*
X06162Y03566*
X06202*
X06119Y03743D02*
Y03819D01*
X06077Y03701D02*
X06119Y03743D01*
X06031Y03701D02*
X06077D01*
X05804D02*
X0588D01*
X05722Y03783D02*
X05804Y03701D01*
X05246Y04276D02*
X05299Y04223D01*
X04713Y04276D02*
X05246D01*
X04074Y02842D02*
X04149D01*
X04064Y02851D02*
X04074Y02842D01*
X04149Y02789D02*
X0415Y0279D01*
X04176*
X04187Y02801*
Y0282*
X04206Y02838*
X04222*
X04234Y02851*
X04339D02*
X04391D01*
X04401Y02842*
X04434*
X05887Y03701D02*
Y03708D01*
X0609Y03561D02*
X06094Y03565D01*
X0609Y03556D02*
Y03561D01*
X04234Y02851D02*
X04339D01*
X02674Y03501D02*
Y03506D01*
X02639Y03535D02*
X02645D01*
X02674Y03506*
X04234Y02725D02*
Y0278D01*
X04339Y02725D02*
Y0278D01*
X03812Y03291D02*
X03969Y03133D01*
X02139Y03663D02*
Y03664D01*
X02209Y03645D02*
X02211Y03643D01*
X02328*
X02329Y03642*
X02139Y03663D02*
X02157Y03645D01*
X02209*
X01249Y04254D02*
X01293D01*
X01294Y04256*
X03969Y03098D02*
X04029Y03039D01*
X04031*
X04039Y0303*
X03732Y03291D02*
X03812D01*
X03702Y03261D02*
X03732Y03291D01*
X04039Y03029D02*
Y0303D01*
X03969Y03098D02*
Y03133D01*
X0428Y03246D02*
X04449D01*
X04039Y03029D02*
X04096D01*
X04109Y03043*
Y03044*
X03959Y02851D02*
Y02948D01*
X04039Y03028*
Y03029*
X03959Y02851D02*
X04064D01*
X04434Y02789D02*
X04503D01*
X05274Y03512D02*
X05299Y03537D01*
X05274Y03511D02*
Y03512D01*
X02633Y03606D02*
X02639D01*
X02598Y03642D02*
X02633Y03606D01*
X02645D02*
X02659Y03592D01*
X02639Y03606D02*
X02645D01*
X04253Y03774D02*
X04254Y03776D01*
X06424Y02181D02*
X06547D01*
X06424Y02181D02*
X06424Y02181D01*
X02139Y03664D02*
X02142Y03666D01*
X01048Y04254D02*
X01249D01*
X00846D02*
X01048D01*
X00644D02*
X00846D01*
X03189Y03855D02*
Y04101D01*
Y03855D02*
X03219Y03826D01*
X03144Y04146D02*
Y04221D01*
Y04146D02*
X03189Y04101D01*
X02694Y0375D02*
Y03757D01*
X02722Y03786*
X02781*
X02809Y03757*
Y0375D02*
Y03757D01*
X03044Y04221D02*
X03144D01*
X06294Y03701D02*
X06341D01*
G54D163*
X04413Y03776D02*
Y03803D01*
X04429Y03818*
X04464*
X04477Y03806*
X04508D02*
X04523Y03791D01*
X04477Y03806D02*
X04508D01*
X00653Y02538D02*
X00653Y02538D01*
Y02593*
X00654Y02365D02*
Y0242D01*
X00653Y02422D02*
X00654Y0242D01*
X00653Y0201D02*
X00654Y02012D01*
Y02073*
X00653Y01894D02*
X00654Y01893D01*
Y01839D02*
Y01893D01*
X00653Y01491D02*
Y01551D01*
X00653Y01491D02*
X00653Y01491D01*
X00653Y01375D02*
X00654Y01373D01*
Y01314D02*
Y01373D01*
X00653Y00963D02*
X00655Y00965D01*
Y01028*
X00654Y0079D02*
Y00846D01*
X00653Y00847D02*
X00654Y00846D01*
X03771Y03082D02*
X03775Y03078D01*
X03877*
G54D164*
X02112Y00269D03*
G54D165*
X01836Y00269D03*
G54D166*
X00199Y02481D03*
Y01956D03*
Y01431D03*
Y00906D03*
G54D167*
X0299Y02437D03*
X03571Y02096D03*
Y01308D03*
X02202Y02437D03*
X01696Y01308D03*
Y02096D03*
X02202Y00957D03*
X0299D03*
G54D168*
X03784Y04126D03*
X03958D03*
G54D169*
X02994Y04086D03*
X03294D03*
G54D170*
X05327Y01007D03*
X04327Y02307D03*
X05127Y01007D03*
X04927D03*
X04727Y02307D03*
X04927D03*
X05127D03*
X05327D03*
G54D171*
X04327Y01007D03*
G54D172*
X04298Y02595D03*
X0418D03*
X04062D03*
X03979Y0089D03*
Y02489D03*
X05578D03*
Y01689D03*
Y0089D03*
G54D173*
X05723Y03844D03*
Y04025D03*
X06569Y03806D03*
Y03589D03*
X06734Y03806D03*
Y03589D03*
X069D03*
Y03806D03*
G54D174*
X06119Y03819D03*
G54D175*
X06119Y04056D03*
G54D176*
X05934Y03937D03*
G54D177*
X02043Y04057D03*
Y04157D03*
X01457Y04053D03*
Y04153D03*
G54D178*
X02043Y04257D03*
X01457Y04253D03*
G54D179*
X06569Y04093D03*
X069D03*
G54D180*
X00285Y04152D03*
Y00368D03*
G54D181*
X02645Y0227D03*
X02618Y02299D03*
X02671Y02291D03*
X06978Y0183D03*
X02314Y00933D03*
X02413D03*
X02515D03*
X02905Y00937D03*
X02901Y01106D03*
X0285D03*
X02787D03*
X02728D03*
X02665D03*
X0261D03*
X02511Y01105D03*
X02409Y01106D03*
X02311D03*
X02322Y02429D03*
X02421D03*
X02484D03*
X02783Y02433D03*
X02874Y0229D03*
X02779Y02601D03*
X02688D03*
X0259D03*
X02488Y02574D03*
X02385Y02613D03*
X02279Y02614D03*
X03051Y02732D03*
X03414Y02892D03*
Y02736D03*
X04385Y03661D03*
X04393Y03976D03*
X04318Y03507D03*
X04116Y03597D03*
X03657Y03296D03*
X03747Y01679D03*
X03718Y01713D03*
X03712Y01673D03*
X0359Y01662D03*
X04523Y03736D03*
X0307Y03393D03*
X04438Y03354D03*
X03542Y03318D03*
X03437Y03476D03*
X03622Y03486D03*
X04437Y03661D03*
X04053Y03641D03*
X0333Y03301D03*
X03344Y02996D03*
X03342Y02263D03*
X03368Y0305D03*
X01015Y01705D03*
X01721Y01685D03*
X01003Y01177D03*
X01893Y01685D03*
X0167D03*
X03877Y03078D03*
X03799Y03201D03*
X02633Y02921D03*
X02414Y03199D03*
X02413Y03295D03*
X02591Y03186D03*
X02462Y03172D03*
X0259Y03288D03*
X02418Y03118D03*
X0522Y04086D03*
X02258Y03741D03*
X0272Y03494D03*
X06335Y03147D03*
X06262Y0322D03*
X06287Y03195D03*
X06274Y02949D03*
X06362Y02952D03*
X0645Y02462D03*
Y02535D03*
X06452Y02606D03*
X06451Y02673D03*
X0645Y0274D03*
X06587Y01529D03*
X06594Y01673D03*
Y0161D03*
Y01775D03*
Y0172D03*
X03602Y00641D03*
X02948Y02456D03*
X02252Y02613D03*
X01674Y01989D03*
X03379Y01386D03*
X03732Y01418D03*
X02579Y02281D03*
X02708Y00976D03*
X02803Y02307D03*
X02575Y02412D03*
X03719Y01996D03*
X02685Y02311D03*
X03803Y01691D03*
X02958Y02621D03*
X0245Y02282D03*
X01714Y01595D03*
X03773Y01666D03*
X02606Y00931D03*
X02881Y02566D03*
X03554Y01941D03*
X0292Y02428D03*
X03864Y01511D03*
X03404Y01363D03*
X02841Y02263D03*
X02767Y00976D03*
X0341Y01713D03*
X03414Y01805D03*
X02799Y00976D03*
X03298Y01971D03*
X02894Y02431D03*
X02759Y00795D03*
X03571Y02058D03*
X02726Y02293D03*
X0274Y00976D03*
X02826Y00795D03*
X02821Y02601D03*
X02985Y02287D03*
X02494Y02696D03*
X01822Y01674D03*
X02625Y00795D03*
X03804Y0184D03*
X02702Y02289D03*
X02893Y00795D03*
X02732D03*
X02599Y02436D03*
X01718Y01792D03*
X02475Y02291D03*
X01879Y01811D03*
X03719Y01921D03*
X03554Y01891D03*
X01568Y02067D03*
X01675Y01891D03*
X01567Y01285D03*
X02826Y00976D03*
X02394Y0272D03*
X02942Y02286D03*
X03554Y01991D03*
X03571Y02033D03*
X02692Y00795D03*
X02598D03*
X01719Y01536D03*
X02272Y02463D03*
X02681Y00976D03*
X03594Y01514D03*
X02409Y02314D03*
X03406Y01461D03*
X03392Y01871D03*
X02494Y02661D03*
X03407Y01411D03*
X02499Y02236D03*
X02409Y02283D03*
X02649Y00976D03*
X01718Y01497D03*
X01619Y02121D03*
X02622Y00976D03*
X01798Y01304D03*
X01671Y01792D03*
X02665Y00795D03*
X01671Y01399D03*
X01754Y02126D03*
X02799Y00795D03*
X03924Y01536D03*
X03549Y01441D03*
X01897Y01516D03*
X02624Y02461D03*
X03329Y01826D03*
X03719Y01766D03*
X01884Y02071D03*
X03834Y01481D03*
X0167Y01595D03*
X02862Y00795D03*
X03894Y01566D03*
X01716Y01399D03*
X03224Y01661D03*
X03379Y01336D03*
X01671Y01497D03*
X0233Y02215D03*
X03413Y01573D03*
X03197Y01714D03*
X01721Y01989D03*
Y0189D03*
X03549Y01413D03*
X03439Y0187D03*
X03252Y01661D03*
X03554Y01841D03*
X04039Y03784D03*
X02692Y02721D03*
X02511Y00405D03*
X0261Y00279D03*
X02578D03*
X0298Y00409D03*
X02821Y00407D03*
X02748Y00282D03*
X02469Y0041D03*
X02905Y00279D03*
X02878Y00249D03*
X02854Y00405D03*
X02779Y00279D03*
X02665Y00405D03*
X02704D03*
X0235D03*
X02389D03*
X02937Y00279D03*
X02957Y00251D03*
X03019Y00405D03*
X02447Y00242D03*
X02413Y00279D03*
X02444D03*
X02636Y00247D03*
X02799Y00251D03*
X02546Y00244D03*
X03097Y00251D03*
X01797Y00355D03*
X02034Y00246D03*
X01916Y00244D03*
X02309Y00246D03*
X01393Y01816D03*
X0099Y00687D03*
X04794Y02808D03*
X03183Y03135D03*
X03277Y02963D03*
X03197Y0297D03*
X03491Y03103D03*
X03188Y03187D03*
X0323Y03235D03*
X03358Y03448D03*
X02419Y02788D03*
X02146Y02753D03*
X03275Y03141D03*
X03056Y01811D03*
X02254Y03536D03*
X02579Y03486D03*
X02389Y03481D03*
X02321Y03361D03*
X02434Y03546D03*
X02634Y03406D03*
X00996Y02256D03*
X02004Y01336D03*
X02028Y01361D03*
X02549Y01755D03*
X02473Y0298D03*
X02146Y04103D03*
X02253Y04086D03*
X01408Y0398D03*
X01345Y04175D03*
X00937Y02317D03*
X02353Y04017D03*
X01726Y04329D03*
X01788D03*
X04477Y03135D03*
X04064Y02722D03*
X06628Y01372D03*
X04039Y02406D03*
X04134Y01651D03*
X03994Y01551D03*
X04134Y01751D03*
X04151Y01623D03*
X03968Y01671D03*
X03969Y01552D03*
X03944Y01816D03*
X04131Y01686D03*
X04179Y01601D03*
X04034Y01546D03*
X03996Y01711D03*
X04064Y01796D03*
Y01511D03*
X03263Y03303D03*
X0396Y02724D03*
X01569Y04171D03*
X02076Y00255D03*
Y00287D03*
X02112D03*
X02151D03*
X02112Y00255D03*
X02151D03*
X01832D03*
X01852D03*
X01872D03*
X01832Y00287D03*
X01852D03*
X01872D03*
X06647Y03129D03*
X04339Y02725D03*
X04503Y02789D03*
X03829Y03806D03*
X05577Y02214D03*
X02694Y01481D03*
X02384Y01941D03*
X0383Y03762D03*
X06334Y03266D03*
X03744Y03261D03*
X03395Y04222D03*
X04272Y03135D03*
X05634Y02236D03*
X02626Y0177D03*
X06304Y03121D03*
X03939D03*
X04208Y03135D03*
X02604Y01734D03*
X06649Y03003D03*
X04152Y03135D03*
X02299Y01916D03*
X01248Y02D03*
X02579Y0179D03*
X04068Y03135D03*
X02674Y03501D03*
X04234Y02725D03*
X06456Y03009D03*
X01691Y04079D03*
X02259Y03261D03*
X03374Y03273D03*
X06476Y03231D03*
X04333Y03135D03*
X01557Y04229D03*
X03806Y03235D03*
X01261Y02482D03*
X04114Y03135D03*
X06648Y03341D03*
X02888Y04221D03*
X01749Y0411D03*
X0257Y04283D03*
X01459Y03147D03*
X0144Y03557D03*
X01903Y04018D03*
X0229Y04217D03*
X03623Y02587D03*
X03491Y03297D03*
X03744Y03342D03*
X03394Y03447D03*
X03717Y03072D03*
X02799Y03616D03*
X03589Y01711D03*
X05733Y03556D03*
X05676Y03546D03*
X03603Y00682D03*
X02478Y00937D03*
X06694Y0183D03*
X06699Y01881D03*
X06949Y02095D03*
X06607Y02176D03*
X06395Y02111D03*
X06048Y02171D03*
X06003Y0243D03*
X06274Y02391D03*
X0491Y04203D03*
X04387Y04206D03*
X03777Y04023D03*
X04085Y03892D03*
X04194Y03884D03*
X04431Y03135D03*
X0286Y03787D03*
X02724Y03729D03*
X03531Y0366D03*
X03269Y03788D03*
X01242Y01472D03*
X01256Y00942D03*
X00654Y0079D03*
X00655Y01028D03*
X00654Y01314D03*
X00653Y01551D03*
X00654Y01839D03*
Y02073D03*
Y02365D03*
X00653Y02593D03*
X02206Y01298D03*
X02205Y032D03*
X02502Y01316D03*
X02525Y02463D03*
X03498Y02341D03*
X02429Y02621D03*
X01004Y00906D03*
X02446Y01437D03*
X01008Y0143D03*
X02409Y01967D03*
X01009Y01956D03*
X0102Y02481D03*
X02643Y01616D03*
X02666Y0164D03*
X01884Y03601D03*
X01754Y03661D03*
X03424Y03636D03*
X01549Y03621D03*
X03239Y03596D03*
X01574D03*
X03539Y03806D03*
X03219D03*
X02722Y03786D03*
X02139Y03611D03*
X02084Y03896D03*
X02083Y01411D03*
X02059Y01386D03*
Y03871D03*
X02029Y03836D03*
X01294Y04256D03*
X02004Y03816D03*
X05274Y03511D03*
X02679Y03661D03*
X02774Y03566D03*
X02993Y03751D03*
X03699D03*
X03014Y03831D03*
X03699Y03836D03*
X04254Y03776D03*
X02894Y01561D03*
X02919Y01536D03*
X02274Y01506D03*
X02719Y01591D03*
X06424Y02181D03*
X04754Y04115D03*
X01779Y04156D03*
X03504Y04086D03*
X03854Y03151D03*
X03829Y03176D03*
X06439Y03191D03*
X06354Y03331D03*
X06444Y03291D03*
X03302Y03344D03*
X06409Y03371D03*
X06447Y03396D03*
X06479Y03426D03*
X06509Y03456D03*
X03469D03*
X01849Y03701D03*
X06294D03*
G54D182*
X05964Y03555D03*
X06196Y02484D03*
X06838Y01649D03*
G54D183*
X02531Y03853D03*
Y0283D03*
X00149D03*
Y03853D03*
M02*